G04 ================== begin FILE IDENTIFICATION RECORD ==================*
G04 Layout Name:  13130-1b.brd*
G04 Film Name:    DIF_REF_L3*
G04 File Format:  Gerber RS274X*
G04 File Origin:  Cadence Allegro 16.5-S037*
G04 Origin Date:  Thu Nov 13 18:47:01 2014*
G04 *
G04 Layer:  BOARD GEOMETRY/OUTLINE*
G04 Layer:  BOARD GEOMETRY/DIF_REF_L3*
G04 Layer:  BOARD GEOMETRY/PANEL_OUTLINE*
G04 *
G04 Offset:    (0.00 0.00)*
G04 Mirror:    No*
G04 Mode:      Positive*
G04 Rotation:  0*
G04 FullContactRelief:  No*
G04 UndefLineWidth:     6.00*
G04 ================== end FILE IDENTIFICATION RECORD ====================*
%FSLAX35Y35*MOIN*%
%IR0*IPPOS*OFA0.00000B0.00000*MIA0B0*SFA1.00000B1.00000*%
%ADD10C,.004*%
%ADD11C,.006*%
%ADD12C,.0045*%
G75*
%LPD*%
G75*
G54D10*
G01X321300Y215468D02*
X328439Y208329D01*
G01X335517Y202383D02*
X322100Y215800D01*
G01X321300Y216700D02*
Y215468D01*
G01X320300Y217700D02*
X321300Y216700D01*
G01X316850Y217700D02*
X320300D01*
G01X316600Y217450D02*
X316850Y217700D01*
G01X316650Y218750D02*
X316600D01*
G01X316900Y218500D02*
X316650Y218750D01*
G01X320632Y218500D02*
X316900D01*
G01X322100Y217032D02*
X320632Y218500D01*
G01X322100Y215800D02*
Y217032D01*
G01X316400Y220200D02*
X316300D01*
G01X316650Y220450D02*
X316400Y220200D01*
G01X317770Y220450D02*
X316650D01*
G01X318160Y220060D02*
X317770Y220450D01*
G01X319360Y220060D02*
X318160D01*
G01X319750Y220450D02*
X319360Y220060D01*
G01X321450Y220450D02*
X319750D01*
G01X323893Y218007D02*
X321450Y220450D01*
G01X323893Y217456D02*
Y218007D01*
G01X324741Y216607D02*
X323893Y217456D01*
G01X325293Y216607D02*
X324741D01*
G01X326141Y215759D02*
X325293Y216607D01*
G01X316400Y221500D02*
X316300D01*
G01X316650Y221250D02*
X316400Y221500D01*
G01X321782Y221250D02*
X316650D01*
G01X328822Y214210D02*
X321782Y221250D01*
G01X325491Y226524D02*
X325421Y226594D01*
G01X325844Y226524D02*
X325491D01*
G01X338400Y197700D02*
X339334Y198634D01*
G01X336200Y197700D02*
X338400D01*
G01X335400Y196900D02*
X336200Y197700D01*
G01X335400Y196300D02*
Y196900D01*
G01X336556Y198500D02*
X335739Y199317D01*
G01X338068Y198500D02*
X336556D01*
G01X338534Y198966D02*
X338068Y198500D01*
G01X338534Y200632D02*
Y198966D01*
G01X337583Y201583D02*
X338534Y200632D01*
G01X335185Y201583D02*
X337583D01*
G01X332088Y204680D02*
X335185Y201583D01*
G01X331536Y204680D02*
X332088D01*
G01X330688Y205529D02*
X331536Y204680D01*
G01X330688Y206080D02*
Y205529D01*
G01X329839Y206929D02*
X330688Y206080D01*
G01X329288Y206929D02*
X329839D01*
G01X328439Y207777D02*
X329288Y206929D01*
G01X328439Y208329D02*
Y207777D01*
G01X337915Y202383D02*
X335517D01*
G01X339334Y200964D02*
X337915Y202383D01*
G01X339334Y198634D02*
Y200964D01*
G01X331658Y212660D02*
X330908Y213410D01*
G01X333700Y212200D02*
Y215700D01*
G01X335800Y210100D02*
X333700Y212200D01*
G01X338322Y210100D02*
X335800D01*
G01X338967Y209455D02*
X338322Y210100D01*
G01X334500Y212532D02*
Y216032D01*
G01X336132Y210900D02*
X334500Y212532D01*
G01X338152Y210900D02*
X336132D01*
G01X338926Y211674D02*
X338152Y210900D01*
G01X342618Y210750D02*
X339000Y214368D01*
G01X326141Y215207D02*
Y215759D01*
G01X326990Y214359D02*
X326141Y215207D01*
G01X327541Y214359D02*
X326990D01*
G01X328490Y213410D02*
X327541Y214359D01*
G01X330908Y213410D02*
X328490D01*
G01X330966Y214210D02*
X328822D01*
G01X331616Y214860D02*
X330966Y214210D01*
G01X334234Y218134D02*
X325844Y226524D01*
G01X334234Y217466D02*
Y218134D01*
G01X335350Y216350D02*
X334234Y217466D01*
G01X336722Y216350D02*
X335350D01*
G01X337341Y215731D02*
X336722Y216350D01*
G01X326411Y227443D02*
X326340Y227514D01*
G01X326411Y227089D02*
Y227443D01*
G01X335034Y218466D02*
X326411Y227089D01*
G01X335034Y217798D02*
Y218466D01*
G01X335682Y217150D02*
X335034Y217798D01*
G01X336496Y217150D02*
X335682D01*
G01X337307Y217961D02*
X336496Y217150D01*
G01X326227Y223173D02*
X325873D01*
G01X333700Y215700D02*
X326227Y223173D01*
G01X326829Y224057D02*
X326793Y224093D01*
G01X326829Y223703D02*
Y224057D01*
G01X334500Y216032D02*
X326829Y223703D01*
G01X331509Y224791D02*
X331184D01*
G01X334200Y222100D02*
X331509Y224791D01*
G01X336000Y222100D02*
X334200D01*
G01X339000Y219100D02*
X336000Y222100D01*
G01X339000Y214368D02*
Y219100D01*
G01X332146Y225668D02*
X332104Y225710D01*
G01X332146Y225286D02*
Y225668D01*
G01X334532Y222900D02*
X332146Y225286D01*
G01X336332Y222900D02*
X334532D01*
G01X339800Y219432D02*
X336332Y222900D01*
G01X339800Y214700D02*
Y219432D01*
G01X342950Y211550D02*
X339800Y214700D01*
G01X340600Y215106D02*
X341455Y214251D01*
G01X340600Y220000D02*
Y215106D01*
G01X334761Y225839D02*
X340600Y220000D01*
G01X334408Y225839D02*
X334761D01*
G01X334337Y225910D02*
X334408Y225839D01*
G01X335327Y226405D02*
X341400Y220332D01*
G01X335327Y226759D02*
Y226405D01*
G01X335256Y226830D02*
X335327Y226759D01*
G01X337700Y225800D02*
Y232758D01*
G01X344600Y218900D02*
X337700Y225800D01*
G01X338500Y226132D02*
Y233090D01*
G01X344932Y219700D02*
X338500Y226132D01*
G01X336539Y233567D02*
X336502Y233604D01*
G01X336891Y233567D02*
X336539D01*
G01X337700Y232758D02*
X336891Y233567D01*
G01X337493Y234452D02*
X337421Y234524D01*
G01X337493Y234097D02*
Y234452D01*
G01X338500Y233090D02*
X337493Y234097D01*
G01X347120Y210750D02*
X342618D01*
G01X347593Y210277D02*
X347120Y210750D01*
G01X346738Y211550D02*
X342950D01*
G01X347664Y212476D02*
X346738Y211550D01*
G01X349550Y212950D02*
Y216150D01*
G01X351050Y211450D02*
X349550Y212950D01*
G01X352851Y211450D02*
X351050D01*
G01X353594Y210707D02*
X352851Y211450D01*
G01X350350Y213282D02*
Y216482D01*
G01X351382Y212250D02*
X350350Y213282D01*
G01X352737Y212250D02*
X351382D01*
G01X353385Y212898D02*
X352737Y212250D01*
G01X342681Y214251D02*
X343242Y213690D01*
G01X341455Y214251D02*
X342681D01*
G01X342339Y215051D02*
X343198Y215910D01*
G01X341787Y215051D02*
X342339D01*
G01X341400Y215438D02*
X341787Y215051D01*
G01X341400Y220332D02*
Y215438D01*
G01X346800Y218900D02*
X344600D01*
G01X349550Y216150D02*
X346800Y218900D01*
G01X347132Y219700D02*
X344932D01*
G01X350350Y216482D02*
X347132Y219700D01*
G01X414722Y88910D02*
Y90250D01*
G01X416932Y86700D02*
X414722Y88910D01*
G01X436456Y86700D02*
X416932D01*
G01X413200Y89300D02*
Y96578D01*
G01X416600Y85900D02*
X413200Y89300D01*
G01X435900Y85900D02*
X416600D01*
G01X413200Y96578D02*
X414622Y98000D01*
G01X412850Y225900D02*
X412050Y225100D01*
G01X412850Y227450D02*
Y225900D01*
G01X413950Y220250D02*
X412100Y218400D01*
G01X413950Y226994D02*
Y220250D01*
G01X431615Y149950D02*
X437202Y144363D01*
G01X425250Y149950D02*
X431615D01*
G01X423909Y148609D02*
X425250Y149950D01*
G01X421939Y148609D02*
X423909D01*
G01X420861Y149687D02*
X421939Y148609D01*
G01X431283Y149150D02*
X436870Y143563D01*
G01X425582Y149150D02*
X431283D01*
G01X424241Y147809D02*
X425582Y149150D01*
G01X421747Y147809D02*
X424241D01*
G01X420861Y146923D02*
X421747Y147809D01*
G01X436556Y86800D02*
X436456Y86700D01*
G01X436100Y85700D02*
X435900Y85900D01*
G01X445097Y144360D02*
X462646D01*
G01X444044Y143307D02*
X445097Y144360D01*
G01X441693Y143307D02*
X444044D01*
G01X440637Y144363D02*
X441693Y143307D01*
G01X437202Y144363D02*
X440637D01*
G01X445429Y143560D02*
X462978D01*
G01X444376Y142507D02*
X445429Y143560D01*
G01X441361Y142507D02*
X444376D01*
G01X440305Y143563D02*
X441361Y142507D01*
G01X436870Y143563D02*
X440305D01*
G01X463200Y124773D02*
Y126200D01*
G01X466473Y121500D02*
X463200Y124773D01*
G01X457850Y124750D02*
X456500Y126100D01*
G01X462091Y124750D02*
X457850D01*
G01X466300Y120541D02*
X462091Y124750D01*
G01X462927Y144641D02*
X463050D01*
G01X462646Y144360D02*
X462927Y144641D01*
G01X462997Y143541D02*
X463100D01*
G01X462978Y143560D02*
X462997Y143541D01*
G01X460900Y174000D02*
X460000Y174900D01*
G01X465300Y174000D02*
X460900D01*
G01X454700Y173200D02*
X453000Y174900D01*
G01X464968Y173200D02*
X454700D01*
G01X461188Y192512D02*
X460400Y193300D01*
G01X463356Y192512D02*
X461188D01*
G01X468008Y197164D02*
X463356Y192512D01*
G01X454988Y191712D02*
X453400Y193300D01*
G01X463688Y191712D02*
X454988D01*
G01X468040Y196064D02*
X463688Y191712D01*
G01X467618Y121500D02*
X466473D01*
G01X467759Y121641D02*
X467618Y121500D01*
G01X467000Y172300D02*
X465300Y174000D01*
G01X467142Y172300D02*
X467000D01*
G01X467442Y172000D02*
X467142Y172300D01*
G01X466542Y171626D02*
X464968Y173200D01*
G01X466542Y171627D02*
Y171626D01*
G01X467269Y170900D02*
X466542Y171627D01*
G01X468600Y196064D02*
X468040D01*
G54D11*
G01X-31497Y-1D02*
X26377D01*
G01X-35434Y3936D02*
G03X-31497Y-1I3937J0D01*
G01X-35434Y585039D02*
Y3936D01*
G01X-7874Y588976D02*
X-31497D01*
G01D02*
G03X-35434Y585039I0J-3937D01*
G01X-12698Y15747D02*
G03I-6988J0D01*
G01Y573227D02*
G03I-6988J0D01*
G01X822835Y290551D02*
X3937D01*
G03X0Y286614I0J-3937D01*
G01Y61811D01*
G03X3937Y57874I3937J0D01*
G01X53937D01*
G02X57874Y53937I0J-3937D01*
G01Y16142D01*
X338189D01*
Y39961D01*
G02X345669I3740J0D01*
G01Y16142D01*
X389764D01*
Y42126D01*
G02X393701Y46063I3937J0D01*
G01X409449D01*
G02X413386Y42126I0J-3937D01*
G01Y3937D01*
G03X417323Y0I3937J0D01*
G01X822835D01*
G03X826772Y3937I0J3937D01*
G01Y286614D01*
G03X822835Y290551I-3937J0D01*
G01X826773Y286614D02*
G03X822836Y290551I-3937J0D01*
G01X3938D01*
G03X1Y286614I0J-3937D01*
G01Y61811D01*
G03X3938Y57874I3937J0D01*
G01X53938D01*
G02X57875Y53937I0J-3937D01*
G01Y12598D01*
X59844Y10629D01*
X336222D01*
X338190Y12598D01*
Y39960D01*
G02X345671I3740J0D01*
G01Y12598D01*
X347639Y10629D01*
X387797D01*
X389765Y12598D01*
Y42126D01*
G02X393702Y46063I3937J0D01*
G01X409450D01*
G02X413387Y42126I0J-3937D01*
G01Y3937D01*
G03X417324Y0I3937J0D01*
G01X822836D01*
G03X826773Y3937I0J3937D01*
G01Y286614D01*
G01D02*
G03X822836Y290551I-3937J0D01*
G01X3938D01*
G03X1Y286614I0J-3937D01*
G01Y61811D01*
G03X3938Y57874I3937J0D01*
G01X53938D01*
G02X57875Y53937I0J-3937D01*
G01Y12598D01*
X59844Y10629D01*
X336222D01*
X338190Y12598D01*
Y39960D01*
G02X345671I3740J0D01*
G01Y12598D01*
X347639Y10629D01*
X387797D01*
X389765Y12598D01*
Y42126D01*
G02X393702Y46063I3937J0D01*
G01X409450D01*
G02X413387Y42126I0J-3937D01*
G01Y3937D01*
G03X417324Y0I3937J0D01*
G01X822836D01*
G03X826773Y3937I0J3937D01*
G01Y286614D01*
G01X22440Y49999D02*
X-3937D01*
G01X-7874Y53936D02*
Y72440D01*
G01Y53936D02*
G03X-3937Y49999I3937J0D01*
G01X0Y72440D02*
G03X-7874I-3937J0D01*
G01Y103149D02*
G03X0I3937J0D01*
G01X-7874D02*
Y210235D01*
G01X0D02*
G03X-7874I-3937J0D01*
G01Y240944D02*
Y348031D01*
G01Y240944D02*
G03X0I3937J0D01*
G01X-3Y302361D02*
G03X3934Y298424I3937J0D01*
G01X822832D01*
G03X826769Y302361I0J3937D01*
G01Y527164D01*
G03X822832Y531101I-3937J0D01*
G01X772832D01*
G02X768895Y535038I0J3937D01*
G01Y576377D01*
X766926Y578346D01*
X490548D01*
X488580Y576377D01*
Y549015D01*
G02X481099I-3740J0D01*
G01Y576377D01*
X479131Y578346D01*
X438973D01*
X437005Y576377D01*
Y546849D01*
G02X433068Y542912I-3937J0D01*
G01X417320D01*
G02X413383Y546849I0J3937D01*
G01Y585038D01*
G03X409446Y588975I-3937J0D01*
G01X3934D01*
G03X-3Y585038I0J-3937D01*
G01Y302361D01*
G01X0Y348031D02*
G03X-7874I-3937J0D01*
G01Y378739D02*
Y485826D01*
G01Y378739D02*
G03X0I3937J0D01*
G01Y485826D02*
G03X-7874I-3937J0D01*
G01Y516535D02*
Y588976D01*
G01Y516535D02*
G03X0I3937J-1D01*
G01X17137Y687650D02*
Y675650D01*
G01X14837Y687650D02*
X19437D01*
G01X21437Y675650D02*
Y687650D01*
G01Y681850D02*
X21937Y682850D01*
X22437Y683450D01*
X23237Y683650D01*
X23837Y683450D01*
X24537Y682650D01*
X24837Y681450D01*
Y675650D01*
G01X29137Y683650D02*
Y675650D01*
G01Y686850D02*
X28937Y687050D01*
Y687450D01*
X29137Y687650D01*
X29337Y687450D01*
Y687050D01*
X29137Y686850D01*
G01X33637Y677050D02*
X34137Y676250D01*
X34837Y675650D01*
X35437D01*
X36037Y676050D01*
X36437Y676650D01*
X36637Y677450D01*
X36537Y678650D01*
X36137Y679250D01*
X34337Y680450D01*
X33937Y681850D01*
X34137Y682850D01*
X34537Y683450D01*
X35137Y683650D01*
X35737Y683450D01*
X36337Y682850D01*
G01X45737Y672650D02*
X46437Y671850D01*
X47237Y671650D01*
X47937Y671850D01*
X48537Y672850D01*
X48937Y674250D01*
Y683650D01*
G01Y682050D02*
X48537Y682850D01*
X47937Y683450D01*
X47237Y683650D01*
X46437Y683250D01*
X45937Y682450D01*
X45537Y681050D01*
X45337Y679650D01*
X45437Y678450D01*
X45837Y677050D01*
X46437Y676050D01*
X47237Y675650D01*
X47837Y675850D01*
X48537Y676650D01*
X48937Y677450D01*
G01X51637Y681050D02*
X54837D01*
X54537Y682450D01*
X54037Y683250D01*
X53337Y683650D01*
X52637Y683450D01*
X52037Y682850D01*
X51637Y681450D01*
X51437Y680250D01*
Y679050D01*
X51637Y677850D01*
X52137Y676650D01*
X52737Y675850D01*
X53437Y675650D01*
X54137Y676050D01*
X54837Y677250D01*
G01X57737Y675650D02*
Y683650D01*
G01Y682050D02*
X58237Y682850D01*
X58737Y683450D01*
X59437Y683650D01*
X59937Y683450D01*
X60537Y682850D01*
G01X63337Y675650D02*
Y687650D01*
G01Y681650D02*
X63837Y682850D01*
X64437Y683450D01*
X65037Y683650D01*
X65937Y683250D01*
X66537Y682450D01*
X66937Y681050D01*
Y679450D01*
X66737Y677850D01*
X66337Y676650D01*
X65637Y675850D01*
X65037Y675650D01*
X64437Y675850D01*
X63837Y676450D01*
X63337Y677450D01*
G01X69637Y681050D02*
X72837D01*
X72537Y682450D01*
X72037Y683250D01*
X71337Y683650D01*
X70637Y683450D01*
X70037Y682850D01*
X69637Y681450D01*
X69437Y680250D01*
Y679050D01*
X69637Y677850D01*
X70137Y676650D01*
X70737Y675850D01*
X71437Y675650D01*
X72137Y676050D01*
X72837Y677250D01*
G01X75737Y675650D02*
Y683650D01*
G01Y682050D02*
X76237Y682850D01*
X76737Y683450D01*
X77437Y683650D01*
X77937Y683450D01*
X78537Y682850D01*
G01X89137Y683650D02*
Y675650D01*
G01Y686850D02*
X88937Y687050D01*
Y687450D01*
X89137Y687650D01*
X89337Y687450D01*
Y687050D01*
X89137Y686850D01*
G01X93637Y677050D02*
X94137Y676250D01*
X94837Y675650D01*
X95437D01*
X96037Y676050D01*
X96437Y676650D01*
X96637Y677450D01*
X96537Y678650D01*
X96137Y679250D01*
X94337Y680450D01*
X93937Y681850D01*
X94137Y682850D01*
X94537Y683450D01*
X95137Y683650D01*
X95737Y683450D01*
X96337Y682850D01*
G01X105537Y672650D02*
X106237Y671850D01*
X106837Y671650D01*
X107637Y672050D01*
X108237Y673050D01*
X108537Y674850D01*
Y683650D01*
G01Y686850D02*
X108337Y687050D01*
Y687450D01*
X108537Y687650D01*
X108737Y687450D01*
Y687050D01*
X108537Y686850D01*
G01X111437Y683650D02*
Y678050D01*
X111837Y676650D01*
X112437Y675850D01*
X113137Y675650D01*
X113837Y675850D01*
X114437Y676650D01*
X114837Y678050D01*
G01Y675650D02*
Y683650D01*
G01X117637Y677050D02*
X118137Y676250D01*
X118837Y675650D01*
X119437D01*
X120037Y676050D01*
X120437Y676650D01*
X120637Y677450D01*
X120537Y678650D01*
X120137Y679250D01*
X118337Y680450D01*
X117937Y681850D01*
X118137Y682850D01*
X118537Y683450D01*
X119137Y683650D01*
X119737Y683450D01*
X120337Y682850D01*
G01X125137Y687650D02*
Y675650D01*
G01X123737Y683650D02*
X126537D01*
G01X136537Y675650D02*
Y685850D01*
X136737Y686850D01*
X137137Y687450D01*
X137737Y687650D01*
X138337Y687250D01*
X138637Y686250D01*
G01X137437Y682850D02*
X135437D01*
G01X143137Y675650D02*
X142537Y675850D01*
X141937Y676650D01*
X141537Y678050D01*
X141337Y679650D01*
X141537Y681250D01*
X141937Y682650D01*
X142537Y683450D01*
X143137Y683650D01*
X143737Y683450D01*
X144337Y682650D01*
X144737Y681250D01*
X144837Y679650D01*
X144737Y678050D01*
X144337Y676650D01*
X143737Y675850D01*
X143137Y675650D01*
G01X147737D02*
Y683650D01*
G01Y682050D02*
X148237Y682850D01*
X148737Y683450D01*
X149437Y683650D01*
X149937Y683450D01*
X150537Y682850D01*
G01X159037Y672050D02*
X159637Y671650D01*
X160437Y672050D01*
X160937Y672850D01*
X161337Y673850D01*
X161937Y677050D01*
X163237Y683650D01*
G01X160037D02*
X161937Y677050D01*
G01X167137Y675650D02*
X166537Y675850D01*
X165937Y676650D01*
X165537Y678050D01*
X165337Y679650D01*
X165537Y681250D01*
X165937Y682650D01*
X166537Y683450D01*
X167137Y683650D01*
X167737Y683450D01*
X168337Y682650D01*
X168737Y681250D01*
X168837Y679650D01*
X168737Y678050D01*
X168337Y676650D01*
X167737Y675850D01*
X167137Y675650D01*
G01X171437Y683650D02*
Y678050D01*
X171837Y676650D01*
X172437Y675850D01*
X173137Y675650D01*
X173837Y675850D01*
X174437Y676650D01*
X174837Y678050D01*
G01Y675650D02*
Y683650D01*
G01X183737Y675650D02*
Y683650D01*
G01Y682050D02*
X184237Y682850D01*
X184737Y683450D01*
X185437Y683650D01*
X185937Y683450D01*
X186537Y682850D01*
G01X189637Y681050D02*
X192837D01*
X192537Y682450D01*
X192037Y683250D01*
X191337Y683650D01*
X190637Y683450D01*
X190037Y682850D01*
X189637Y681450D01*
X189437Y680250D01*
Y679050D01*
X189637Y677850D01*
X190137Y676650D01*
X190737Y675850D01*
X191437Y675650D01*
X192137Y676050D01*
X192837Y677250D01*
G01X196537Y675650D02*
Y685850D01*
X196737Y686850D01*
X197137Y687450D01*
X197737Y687650D01*
X198337Y687250D01*
X198637Y686250D01*
G01X197437Y682850D02*
X195437D01*
G01X201637Y681050D02*
X204837D01*
X204537Y682450D01*
X204037Y683250D01*
X203337Y683650D01*
X202637Y683450D01*
X202037Y682850D01*
X201637Y681450D01*
X201437Y680250D01*
Y679050D01*
X201637Y677850D01*
X202137Y676650D01*
X202737Y675850D01*
X203437Y675650D01*
X204137Y676050D01*
X204837Y677250D01*
G01X207737Y675650D02*
Y683650D01*
G01Y682050D02*
X208237Y682850D01*
X208737Y683450D01*
X209437Y683650D01*
X209937Y683450D01*
X210537Y682850D01*
G01X213637Y681050D02*
X216837D01*
X216537Y682450D01*
X216037Y683250D01*
X215337Y683650D01*
X214637Y683450D01*
X214037Y682850D01*
X213637Y681450D01*
X213437Y680250D01*
Y679050D01*
X213637Y677850D01*
X214137Y676650D01*
X214737Y675850D01*
X215437Y675650D01*
X216137Y676050D01*
X216837Y677250D01*
G01X219437Y675650D02*
Y683650D01*
G01Y681650D02*
X219837Y682650D01*
X220437Y683450D01*
X221237Y683650D01*
X221937Y683450D01*
X222537Y682650D01*
X222837Y681250D01*
Y675650D01*
G01X228737Y682650D02*
X228037Y683450D01*
X227437Y683650D01*
X226637Y683250D01*
X226037Y682450D01*
X225637Y681050D01*
X225537Y679650D01*
X225637Y678250D01*
X226037Y677050D01*
X226637Y676050D01*
X227437Y675650D01*
X228137Y676050D01*
X228737Y676850D01*
G01X231637Y681050D02*
X234837D01*
X234537Y682450D01*
X234037Y683250D01*
X233337Y683650D01*
X232637Y683450D01*
X232037Y682850D01*
X231637Y681450D01*
X231437Y680250D01*
Y679050D01*
X231637Y677850D01*
X232137Y676650D01*
X232737Y675850D01*
X233437Y675650D01*
X234137Y676050D01*
X234837Y677250D01*
G01X245137Y687650D02*
Y675650D01*
G01X243737Y683650D02*
X246537D01*
G01X251137Y675650D02*
X250537Y675850D01*
X249937Y676650D01*
X249537Y678050D01*
X249337Y679650D01*
X249537Y681250D01*
X249937Y682650D01*
X250537Y683450D01*
X251137Y683650D01*
X251737Y683450D01*
X252337Y682650D01*
X252737Y681250D01*
X252837Y679650D01*
X252737Y678050D01*
X252337Y676650D01*
X251737Y675850D01*
X251137Y675650D01*
G01X262537D02*
Y685850D01*
X262737Y686850D01*
X263137Y687450D01*
X263737Y687650D01*
X264337Y687250D01*
X264637Y686250D01*
G01X263437Y682850D02*
X261437D01*
G01X269137Y683650D02*
Y675650D01*
G01Y686850D02*
X268937Y687050D01*
Y687450D01*
X269137Y687650D01*
X269337Y687450D01*
Y687050D01*
X269137Y686850D01*
G01X273437Y675650D02*
Y683650D01*
G01Y681650D02*
X273837Y682650D01*
X274437Y683450D01*
X275237Y683650D01*
X275937Y683450D01*
X276537Y682650D01*
X276837Y681250D01*
Y675650D01*
G01X282937Y687650D02*
Y675650D01*
G01Y677450D02*
X282537Y676450D01*
X281937Y675850D01*
X281237Y675650D01*
X280437Y676050D01*
X279837Y677050D01*
X279437Y678250D01*
X279337Y679650D01*
X279437Y681050D01*
X279837Y682250D01*
X280437Y683250D01*
X281237Y683650D01*
X281937Y683450D01*
X282437Y683050D01*
X282937Y682250D01*
G01X293137Y687650D02*
Y675650D01*
G01X291737Y683650D02*
X294537D01*
G01X297437Y675650D02*
Y687650D01*
G01Y681850D02*
X297937Y682850D01*
X298437Y683450D01*
X299237Y683650D01*
X299837Y683450D01*
X300537Y682650D01*
X300837Y681450D01*
Y675650D01*
G01X303637Y681050D02*
X306837D01*
X306537Y682450D01*
X306037Y683250D01*
X305337Y683650D01*
X304637Y683450D01*
X304037Y682850D01*
X303637Y681450D01*
X303437Y680250D01*
Y679050D01*
X303637Y677850D01*
X304137Y676650D01*
X304737Y675850D01*
X305437Y675650D01*
X306137Y676050D01*
X306837Y677250D01*
G01X318937Y687650D02*
Y675650D01*
G01Y677450D02*
X318537Y676450D01*
X317937Y675850D01*
X317237Y675650D01*
X316437Y676050D01*
X315837Y677050D01*
X315437Y678250D01*
X315337Y679650D01*
X315437Y681050D01*
X315837Y682250D01*
X316437Y683250D01*
X317237Y683650D01*
X317937Y683450D01*
X318437Y683050D01*
X318937Y682250D01*
G01X323137Y683650D02*
Y675650D01*
G01Y686850D02*
X322937Y687050D01*
Y687450D01*
X323137Y687650D01*
X323337Y687450D01*
Y687050D01*
X323137Y686850D01*
G01X328537Y675650D02*
Y685850D01*
X328737Y686850D01*
X329137Y687450D01*
X329737Y687650D01*
X330337Y687250D01*
X330637Y686250D01*
G01X329437Y682850D02*
X327437D01*
G01X334537Y675650D02*
Y685850D01*
X334737Y686850D01*
X335137Y687450D01*
X335737Y687650D01*
X336337Y687250D01*
X336637Y686250D01*
G01X335437Y682850D02*
X333437D01*
G01X339637Y681050D02*
X342837D01*
X342537Y682450D01*
X342037Y683250D01*
X341337Y683650D01*
X340637Y683450D01*
X340037Y682850D01*
X339637Y681450D01*
X339437Y680250D01*
Y679050D01*
X339637Y677850D01*
X340137Y676650D01*
X340737Y675850D01*
X341437Y675650D01*
X342137Y676050D01*
X342837Y677250D01*
G01X345737Y675650D02*
Y683650D01*
G01Y682050D02*
X346237Y682850D01*
X346737Y683450D01*
X347437Y683650D01*
X347937Y683450D01*
X348537Y682850D01*
G01X351637Y681050D02*
X354837D01*
X354537Y682450D01*
X354037Y683250D01*
X353337Y683650D01*
X352637Y683450D01*
X352037Y682850D01*
X351637Y681450D01*
X351437Y680250D01*
Y679050D01*
X351637Y677850D01*
X352137Y676650D01*
X352737Y675850D01*
X353437Y675650D01*
X354137Y676050D01*
X354837Y677250D01*
G01X357437Y675650D02*
Y683650D01*
G01Y681650D02*
X357837Y682650D01*
X358437Y683450D01*
X359237Y683650D01*
X359937Y683450D01*
X360537Y682650D01*
X360837Y681250D01*
Y675650D01*
G01X365137Y687650D02*
Y675650D01*
G01X363737Y683650D02*
X366537D01*
G01X371137D02*
Y675650D01*
G01Y686850D02*
X370937Y687050D01*
Y687450D01*
X371137Y687650D01*
X371337Y687450D01*
Y687050D01*
X371137Y686850D01*
G01X378937Y675650D02*
Y683650D01*
G01Y682250D02*
X378537Y683050D01*
X377937Y683450D01*
X377237Y683650D01*
X376537Y683250D01*
X375937Y682450D01*
X375537Y681250D01*
X375337Y679650D01*
X375537Y678050D01*
X375937Y676850D01*
X376537Y676050D01*
X377237Y675650D01*
X377937Y675850D01*
X378537Y676450D01*
X378937Y677250D01*
G01X383137Y675650D02*
Y687650D01*
G01X395137D02*
Y675650D01*
G01X393737Y683650D02*
X396537D01*
G01X399737Y675650D02*
Y683650D01*
G01Y682050D02*
X400237Y682850D01*
X400737Y683450D01*
X401437Y683650D01*
X401937Y683450D01*
X402537Y682850D01*
G01X408937Y675650D02*
Y683650D01*
G01Y682250D02*
X408537Y683050D01*
X407937Y683450D01*
X407237Y683650D01*
X406537Y683250D01*
X405937Y682450D01*
X405537Y681250D01*
X405337Y679650D01*
X405537Y678050D01*
X405937Y676850D01*
X406537Y676050D01*
X407237Y675650D01*
X407937Y675850D01*
X408537Y676450D01*
X408937Y677250D01*
G01X414737Y682650D02*
X414037Y683450D01*
X413437Y683650D01*
X412637Y683250D01*
X412037Y682450D01*
X411637Y681050D01*
X411537Y679650D01*
X411637Y678250D01*
X412037Y677050D01*
X412637Y676050D01*
X413437Y675650D01*
X414137Y676050D01*
X414737Y676850D01*
G01X417637Y681050D02*
X420837D01*
X420537Y682450D01*
X420037Y683250D01*
X419337Y683650D01*
X418637Y683450D01*
X418037Y682850D01*
X417637Y681450D01*
X417437Y680250D01*
Y679050D01*
X417637Y677850D01*
X418137Y676650D01*
X418737Y675850D01*
X419437Y675650D01*
X420137Y676050D01*
X420837Y677250D01*
G01X423637Y677050D02*
X424137Y676250D01*
X424837Y675650D01*
X425437D01*
X426037Y676050D01*
X426437Y676650D01*
X426637Y677450D01*
X426537Y678650D01*
X426137Y679250D01*
X424337Y680450D01*
X423937Y681850D01*
X424137Y682850D01*
X424537Y683450D01*
X425137Y683650D01*
X425737Y683450D01*
X426337Y682850D01*
G01X437137Y683650D02*
Y675650D01*
G01Y686850D02*
X436937Y687050D01*
Y687450D01*
X437137Y687650D01*
X437337Y687450D01*
Y687050D01*
X437137Y686850D01*
G01X441437Y675650D02*
Y683650D01*
G01Y681650D02*
X441837Y682650D01*
X442437Y683450D01*
X443237Y683650D01*
X443937Y683450D01*
X444537Y682650D01*
X444837Y681250D01*
Y675650D01*
G01X455137D02*
Y687650D01*
G01X462937Y675650D02*
Y683650D01*
G01Y682250D02*
X462537Y683050D01*
X461937Y683450D01*
X461237Y683650D01*
X460537Y683250D01*
X459937Y682450D01*
X459537Y681250D01*
X459337Y679650D01*
X459537Y678050D01*
X459937Y676850D01*
X460537Y676050D01*
X461237Y675650D01*
X461937Y675850D01*
X462537Y676450D01*
X462937Y677250D01*
G01X465037Y672050D02*
X465637Y671650D01*
X466437Y672050D01*
X466937Y672850D01*
X467337Y673850D01*
X467937Y677050D01*
X469237Y683650D01*
G01X466037D02*
X467937Y677050D01*
G01X471637Y681050D02*
X474837D01*
X474537Y682450D01*
X474037Y683250D01*
X473337Y683650D01*
X472637Y683450D01*
X472037Y682850D01*
X471637Y681450D01*
X471437Y680250D01*
Y679050D01*
X471637Y677850D01*
X472137Y676650D01*
X472737Y675850D01*
X473437Y675650D01*
X474137Y676050D01*
X474837Y677250D01*
G01X477737Y675650D02*
Y683650D01*
G01Y682050D02*
X478237Y682850D01*
X478737Y683450D01*
X479437Y683650D01*
X479937Y683450D01*
X480537Y682850D01*
G01X489137Y687650D02*
Y675650D01*
X493137D01*
G01X494937Y678050D02*
X495537Y676650D01*
X496337Y675850D01*
X497237Y675650D01*
X498037Y675850D01*
X498837Y676850D01*
X499337Y678050D01*
X499437Y679250D01*
X499237Y680650D01*
X498537Y681650D01*
X497837Y682050D01*
X496937D01*
G01X497837D02*
X498437Y682650D01*
X498937Y683650D01*
X499137Y684850D01*
X498937Y686050D01*
X498437Y687050D01*
X497537Y687650D01*
X496637Y687450D01*
X495737Y686650D01*
G01X26377Y-1D02*
Y46062D01*
G01D02*
G03X22440Y49999I-3937J0D01*
G01X102756Y290550D02*
G03Y298424I0J3937D01*
G01X133465D02*
G03Y290550I0J-3937D01*
G01X299606Y290551D02*
G03Y298425I0J3937D01*
G01X330314D02*
G03Y290551I0J-3937D01*
G01X353350Y224807D02*
X347051D01*
G02Y237406I0J6299D01*
G01X353350D01*
G02Y224807I0J-6299D01*
G01X496457Y290550D02*
G03Y298424I0J3937D01*
G01X527166D02*
G03Y290550I0J-3937D01*
G01X693308D02*
G03Y298424I0J3937D01*
G01X724016D02*
G03Y290550I0J-3937D01*
G01X800393Y588976D02*
Y542913D01*
G01D02*
G03X804330Y538976I3937J0D01*
G01X858267Y588976D02*
X800393D01*
G01X804330Y538976D02*
X830708D01*
G01X834645Y72440D02*
G03X826771I-3937J0D01*
G01Y103149D02*
G03X834645I3937J0D01*
G01Y210235D02*
G03X826771I-3937J0D01*
G01Y240944D02*
G03X834645I3937J0D01*
G01Y348031D02*
G03X826771I-3937J0D01*
G01Y378739D02*
G03X834645I3937J0D01*
G01Y485826D02*
G03X826771I-3937J0D01*
G01Y516535D02*
G03X834645I3937J-1D01*
G01Y535039D02*
G03X830708Y538976I-3937J0D01*
G01X834645Y72440D02*
Y-1D01*
G01D02*
X858267D01*
G01X853444Y15747D02*
G03I-6988J0D01*
G01X834645Y210235D02*
Y103149D01*
G01Y348031D02*
Y240944D01*
G01Y485826D02*
Y378739D01*
G01Y535039D02*
Y516535D01*
G01X853444Y573227D02*
G03I-6988J0D01*
G01X862204Y3936D02*
Y585039D01*
G01X858267Y-1D02*
G03X862204Y3936I0J3937D01*
G01Y585039D02*
G03X858267Y588976I-3937J0D01*
G01X379500Y82356D02*
Y83302D01*
G01X384906Y76950D02*
X379500Y82356D01*
G01X392106Y76950D02*
X384906D01*
G01X377670Y88770D02*
X379500Y90600D01*
G01X377670Y82630D02*
Y88770D01*
G01X384450Y75850D02*
X377670Y82630D01*
G01X391650Y75850D02*
X384450D01*
G01X400254Y68802D02*
X392106Y76950D01*
G01X420519Y68802D02*
X400254D01*
G01X399798Y67702D02*
X391650Y75850D01*
G01X420063Y67702D02*
X399798D01*
G01X416563Y231163D02*
X412850Y227450D01*
G01X417019Y230063D02*
X413950Y226994D01*
G01X485569Y231163D02*
X416563D01*
G01X486025Y230063D02*
X417019D01*
G01X428566Y59199D02*
X420063Y67702D01*
G01X444201Y59199D02*
X428566D01*
G01X429022Y60299D02*
X420519Y68802D01*
G01X453663Y60299D02*
X429022D01*
G01X444800Y58600D02*
X444201Y59199D01*
G01X446601Y58600D02*
X444800D01*
G01X447200Y59199D02*
X446601Y58600D01*
G01X453207Y59199D02*
X447200D01*
G01X448400Y86100D02*
X485307D01*
G01X445800Y83500D02*
X448400Y86100D01*
G01X443656Y83500D02*
X445800D01*
G01X441056Y86100D02*
X443656Y83500D01*
G01X438556Y86100D02*
X441056D01*
G01X437856Y86800D02*
X438556Y86100D01*
G01X436556Y86800D02*
X437856D01*
G01X448856Y85000D02*
X484851D01*
G01X446256Y82400D02*
X448856Y85000D01*
G01X443200Y82400D02*
X446256D01*
G01X440600Y85000D02*
X443200Y82400D01*
G01X438100Y85000D02*
X440600D01*
G01X437400Y85700D02*
X438100Y85000D01*
G01X436100Y85700D02*
X437400D01*
G01X454907Y59055D02*
X453663Y60299D01*
G01X454907Y56950D02*
Y59055D01*
G01X455507Y56350D02*
X454907Y56950D01*
G01X456707Y56350D02*
X455507D01*
G01X457307Y56950D02*
X456707Y56350D01*
G01X457307Y58456D02*
Y56950D01*
G01X458551Y59700D02*
X457307Y58456D01*
G01X463500D02*
X462256Y59700D01*
G01X463500Y55400D02*
Y58456D01*
G01X464100Y54800D02*
X463500Y55400D01*
G01X528609Y54800D02*
X464100D01*
G01X453807Y58599D02*
X453207Y59199D01*
G01X453807Y56494D02*
Y58599D01*
G01X455051Y55250D02*
X453807Y56494D01*
G01X457163Y55250D02*
X455051D01*
G01X458407Y56494D02*
X457163Y55250D01*
G01X458407Y58000D02*
Y56494D01*
G01X459007Y58600D02*
X458407Y58000D01*
G01X461800Y58600D02*
X459007D01*
G01X462400Y58000D02*
X461800Y58600D01*
G01X462400Y54944D02*
Y58000D01*
G01X463644Y53700D02*
X462400Y54944D01*
G01X467923Y53700D02*
X463644D01*
G01X462256Y59700D02*
X458551D01*
G01X520259Y144641D02*
X463050D01*
G01X519803Y143541D02*
X463100D01*
G01X468413Y53210D02*
X467923Y53700D01*
G01X470213Y53210D02*
X468413D01*
G01X470703Y53700D02*
X470213Y53210D01*
G01X472503Y53700D02*
X470703D01*
G01X472993Y53210D02*
X472503Y53700D01*
G01X474793Y53210D02*
X472993D01*
G01X475283Y53700D02*
X474793Y53210D01*
G01X477083Y53700D02*
X475283D01*
G01X477573Y53210D02*
X477083Y53700D01*
G01X479373Y53210D02*
X477573D01*
G01X479863Y53700D02*
X479373Y53210D01*
G01X466300Y120541D02*
X487514D01*
G01X467759Y121641D02*
X487970D01*
G01X467442Y172000D02*
X613100D01*
G01X613556Y170900D02*
X467269D01*
G01X565717Y197164D02*
X468008D01*
G01X566173Y196064D02*
X468600D01*
G01X487233Y53700D02*
X479863D01*
G01X487723Y53210D02*
X487233Y53700D01*
G01X489523Y53210D02*
X487723D01*
G01X490013Y53700D02*
X489523Y53210D01*
G01X491813Y53700D02*
X490013D01*
G01X492303Y53210D02*
X491813Y53700D01*
G01X494103Y53210D02*
X492303D01*
G01X494593Y53700D02*
X494103Y53210D01*
G01X528153Y53700D02*
X494593D01*
G01X493807Y77600D02*
X591894D01*
G01X485307Y86100D02*
X493807Y77600D01*
G01X493351Y76500D02*
X591438D01*
G01X484851Y85000D02*
X493351Y76500D01*
G01X487970Y121641D02*
X496841Y112770D01*
G01X487514Y120541D02*
X496385Y111670D01*
G01X486169Y231763D02*
X485569Y231163D01*
G01X486169Y235056D02*
Y231763D01*
G01X487413Y236300D02*
X486169Y235056D01*
G01X489525Y236300D02*
X487413D01*
G01X490769Y235056D02*
X489525Y236300D01*
G01X490769Y231763D02*
Y235056D01*
G01X491369Y231163D02*
X490769Y231763D01*
G01X492569Y231163D02*
X491369D01*
G01X493169Y231763D02*
X492569Y231163D01*
G01X493169Y235056D02*
Y231763D01*
G01X494413Y236300D02*
X493169Y235056D01*
G01X496525Y236300D02*
X494413D01*
G01X487269Y231307D02*
X486025Y230063D01*
G01X487269Y234600D02*
Y231307D01*
G01X487869Y235200D02*
X487269Y234600D01*
G01X489069Y235200D02*
X487869D01*
G01X489669Y234600D02*
X489069Y235200D01*
G01X489669Y231307D02*
Y234600D01*
G01X490913Y230063D02*
X489669Y231307D01*
G01X493025Y230063D02*
X490913D01*
G01X494269Y231307D02*
X493025Y230063D01*
G01X494269Y234600D02*
Y231307D01*
G01X494869Y235200D02*
X494269Y234600D01*
G01X496069Y235200D02*
X494869D01*
G01X510091Y113260D02*
X510581Y112770D01*
G01X508291Y113260D02*
X510091D01*
G01X507801Y112770D02*
X508291Y113260D01*
G01X506001Y112770D02*
X507801D01*
G01X505511Y113260D02*
X506001Y112770D01*
G01X503711Y113260D02*
X505511D01*
G01X503221Y112770D02*
X503711Y113260D01*
G01X501421Y112770D02*
X503221D01*
G01X500931Y113260D02*
X501421Y112770D01*
G01X499131Y113260D02*
X500931D01*
G01X498641Y112770D02*
X499131Y113260D01*
G01X496841Y112770D02*
X498641D01*
G01X496385Y111670D02*
X608268D01*
G01X497769Y235056D02*
X496525Y236300D01*
G01X497769Y231763D02*
Y235056D01*
G01X498369Y231163D02*
X497769Y231763D01*
G01X500669Y231163D02*
X498369D01*
G01X501269Y231763D02*
X500669Y231163D01*
G01X501269Y233356D02*
Y231763D01*
G01X502513Y234600D02*
X501269Y233356D01*
G01X504625Y234600D02*
X502513D01*
G01X505869Y233356D02*
X504625Y234600D01*
G01X505869Y231763D02*
Y233356D01*
G01X506469Y231163D02*
X505869Y231763D01*
G01X517407Y231163D02*
X506469D01*
G01X496669Y234600D02*
X496069Y235200D01*
G01X496669Y231307D02*
Y234600D01*
G01X497913Y230063D02*
X496669Y231307D01*
G01X501125Y230063D02*
X497913D01*
G01X502369Y231307D02*
X501125Y230063D01*
G01X502369Y232900D02*
Y231307D01*
G01X502969Y233500D02*
X502369Y232900D01*
G01X504169Y233500D02*
X502969D01*
G01X504769Y232900D02*
X504169Y233500D01*
G01X504769Y231307D02*
Y232900D01*
G01X506013Y230063D02*
X504769Y231307D01*
G01X517863Y230063D02*
X506013D01*
G01X510581Y112770D02*
X608724D01*
G01X522100Y142800D02*
X520259Y144641D01*
G01X532800Y142800D02*
X522100D01*
G01X521644Y141700D02*
X519803Y143541D01*
G01X533256Y141700D02*
X521644D01*
G01X520344Y234100D02*
X517407Y231163D01*
G01X533815Y234100D02*
X520344D01*
G01X520800Y233000D02*
X517863Y230063D01*
G01X522600Y233000D02*
X520800D01*
G01X523090Y232510D02*
X522600Y233000D01*
G01X524890Y232510D02*
X523090D01*
G01X525380Y233000D02*
X524890Y232510D01*
G01X527180Y233000D02*
X525380D01*
G01X535392Y24000D02*
Y37664D01*
G01X536485Y22907D02*
X535392Y24000D01*
G01X534292Y23999D02*
Y37208D01*
G01X533200Y22907D02*
X534292Y23999D01*
G01X529853Y43203D02*
Y53556D01*
G01X535392Y37664D02*
X529853Y43203D01*
G01X528753Y42747D02*
Y53100D01*
G01X534292Y37208D02*
X528753Y42747D01*
G01X529853Y53556D02*
X528609Y54800D01*
G01X528753Y53100D02*
X528153Y53700D01*
G01X534641Y144641D02*
X532800Y142800D01*
G01X554359Y144641D02*
X534641D01*
G01X535097Y143541D02*
X533256Y141700D01*
G01X536897Y143541D02*
X535097D01*
G01X537387Y143051D02*
X536897Y143541D01*
G01X539187Y143051D02*
X537387D01*
G01X539677Y143541D02*
X539187Y143051D01*
G01X541477Y143541D02*
X539677D01*
G01X535315Y232600D02*
X533815Y234100D01*
G01X545598Y232600D02*
X535315D01*
G01X527670Y232510D02*
X527180Y233000D01*
G01X529470Y232510D02*
X527670D01*
G01X529960Y233000D02*
X529470Y232510D01*
G01X533359Y233000D02*
X529960D01*
G01X534859Y231500D02*
X533359Y233000D01*
G01X546054Y231500D02*
X534859D01*
G01X556200Y142800D02*
X554359Y144641D01*
G01X564300Y142800D02*
X556200D01*
G01X541967Y143051D02*
X541477Y143541D01*
G01X543767Y143051D02*
X541967D01*
G01X544257Y143541D02*
X543767Y143051D01*
G01X546057Y143541D02*
X544257D01*
G01X546547Y143051D02*
X546057Y143541D01*
G01X548347Y143051D02*
X546547D01*
G01X548837Y143541D02*
X548347Y143051D01*
G01X553903Y143541D02*
X548837D01*
G01X555744Y141700D02*
X553903Y143541D01*
G01X564756Y141700D02*
X555744D01*
G01X557805Y244807D02*
X545598Y232600D01*
G01X549226Y234672D02*
X546054Y231500D01*
G01X549919Y234672D02*
X549226D01*
G01X551192Y235945D02*
X549919Y234672D01*
G01X551192Y236638D02*
Y235945D01*
G01X552465Y237911D02*
X551192Y236638D01*
G01X553158Y237911D02*
X552465D01*
G01X554430Y239183D02*
X553158Y237911D01*
G01X554430Y239876D02*
Y239183D01*
G01X558905Y244351D02*
X554430Y239876D01*
G01X556734Y259844D02*
X557805Y258773D01*
G01X556734Y261396D02*
Y259844D01*
G01X555641Y262489D02*
X556734Y261396D01*
G01X566141Y144641D02*
X564300Y142800D01*
G01X576009Y144641D02*
X566141D01*
G01X566597Y143541D02*
X564756Y141700D01*
G01X575553Y143541D02*
X566597D01*
G01X572752Y204199D02*
X565717Y197164D01*
G01X573208Y203099D02*
X566173Y196064D01*
G01X557805Y258773D02*
Y244807D01*
G01X558905Y259229D02*
Y244351D01*
G01X557834Y260300D02*
X558905Y259229D01*
G01X557834Y261397D02*
Y260300D01*
G01X558926Y262489D02*
X557834Y261397D01*
G01X577253Y143397D02*
X576009Y144641D01*
G01X577253Y140400D02*
Y143397D01*
G01X577853Y139800D02*
X577253Y140400D01*
G01X579053Y139800D02*
X577853D01*
G01X579653Y140400D02*
X579053Y139800D01*
G01X579653Y143397D02*
Y140400D01*
G01X580897Y144641D02*
X579653Y143397D01*
G01X585859Y144641D02*
X580897D01*
G01X587700Y142800D02*
X585859Y144641D01*
G01X576153Y142941D02*
X575553Y143541D01*
G01X576153Y139944D02*
Y142941D01*
G01X577397Y138700D02*
X576153Y139944D01*
G01X579509Y138700D02*
X577397D01*
G01X580753Y139944D02*
X579509Y138700D01*
G01X580753Y142941D02*
Y139944D01*
G01X581353Y143541D02*
X580753Y142941D01*
G01X585403Y143541D02*
X581353D01*
G01X587244Y141700D02*
X585403Y143541D01*
G01X620182Y141700D02*
X587244D01*
G01X574512Y204199D02*
X572752D01*
G01X577331Y201379D02*
X574512Y204199D01*
G01X578179Y201379D02*
X577331D01*
G01X579030Y202230D02*
X578179Y201379D01*
G01X579030Y203078D02*
Y202230D01*
G01X576211Y205898D02*
X579030Y203078D01*
G01X576211Y207658D02*
Y205898D01*
G01X580000Y211447D02*
X576211Y207658D01*
G01X580000Y217256D02*
Y211447D01*
G01X574056Y203099D02*
X573208D01*
G01X576875Y200279D02*
X574056Y203099D01*
G01X578635Y200279D02*
X576875D01*
G01X580130Y201774D02*
X578635Y200279D01*
G01X580130Y203534D02*
Y201774D01*
G01X577311Y206354D02*
X580130Y203534D01*
G01X577311Y207202D02*
Y206354D01*
G01X581100Y210991D02*
X577311Y207202D01*
G01X581100Y216800D02*
Y210991D01*
G01X581644Y218900D02*
X580000Y217256D01*
G01X583444Y218900D02*
X581644D01*
G01X583934Y219390D02*
X583444Y218900D01*
G01X585734Y219390D02*
X583934D01*
G01X586224Y218900D02*
X585734Y219390D01*
G01X588024Y218900D02*
X586224D01*
G01X582100Y217800D02*
X581100Y216800D01*
G01X600000Y217800D02*
X582100D01*
G01X601309Y29114D02*
X603897Y26526D01*
G01X602797Y24000D02*
X601704Y22907D01*
G01X602797Y26070D02*
Y24000D01*
G01X597300Y31567D02*
X602797Y26070D01*
G01X601309Y29807D02*
Y29114D01*
G01X600036Y31080D02*
X601309Y29807D01*
G01X599343Y31080D02*
X600036D01*
G01X598400Y32023D02*
X599343Y31080D01*
G01X598400Y39760D02*
Y32023D01*
G01X598890Y40250D02*
X598400Y39760D01*
G01X598890Y42050D02*
Y40250D01*
G01X598400Y42540D02*
X598890Y42050D01*
G01X598400Y44340D02*
Y42540D01*
G01X597300Y70638D02*
Y31567D01*
G01X598890Y44830D02*
X598400Y44340D01*
G01X598890Y46630D02*
Y44830D01*
G01X598400Y47120D02*
X598890Y46630D01*
G01X598400Y48920D02*
Y47120D01*
G01X598890Y49410D02*
X598400Y48920D01*
G01X598890Y51210D02*
Y49410D01*
G01X598400Y51700D02*
X598890Y51210D01*
G01X598400Y53686D02*
Y51700D01*
G01X598890Y54176D02*
X598400Y53686D01*
G01X598890Y55976D02*
Y54176D01*
G01X598400Y56466D02*
X598890Y55976D01*
G01X598400Y60258D02*
Y56466D01*
G01X598890Y60748D02*
X598400Y60258D01*
G01X598890Y62548D02*
Y60748D01*
G01X598400Y63038D02*
X598890Y62548D01*
G01X598400Y66514D02*
Y63038D01*
G01X598890Y67004D02*
X598400Y66514D01*
G01X598890Y68804D02*
Y67004D01*
G01X598400Y69294D02*
X598890Y68804D01*
G01X598400Y71094D02*
Y69294D01*
G01X591894Y77600D02*
X598400Y71094D01*
G01X591438Y76500D02*
X597300Y70638D01*
G01X620638Y142800D02*
X587700D01*
G01X588514Y219390D02*
X588024Y218900D01*
G01X590314Y219390D02*
X588514D01*
G01X590804Y218900D02*
X590314Y219390D01*
G01X592604Y218900D02*
X590804D01*
G01X593094Y219390D02*
X592604Y218900D01*
G01X594894Y219390D02*
X593094D01*
G01X595384Y218900D02*
X594894Y219390D01*
G01X599544Y218900D02*
X595384D01*
G01X600294Y219650D02*
X599544Y218900D01*
G01X605484Y219650D02*
X600294D01*
G01X600750Y218550D02*
X600000Y217800D01*
G01X605028Y218550D02*
X600750D01*
G01X603897Y23999D02*
X604989Y22907D01*
G01X603897Y26526D02*
Y23999D01*
G01X608724Y112770D02*
X643694Y77800D01*
G01X608268Y111670D02*
X643238Y76700D01*
G01X618300Y172600D02*
X618900Y172000D01*
G01X618300Y177456D02*
Y172600D01*
G01X617056Y178700D02*
X618300Y177456D01*
G01X614944Y178700D02*
X617056D01*
G01X613700Y177456D02*
X614944Y178700D01*
G01X613700Y172600D02*
Y177456D01*
G01X613100Y172000D02*
X613700Y172600D01*
G01X614800Y172144D02*
X613556Y170900D01*
G01X614800Y177000D02*
Y172144D01*
G01X615400Y177600D02*
X614800Y177000D01*
G01X616600Y177600D02*
X615400D01*
G01X617200Y177000D02*
X616600Y177600D01*
G01X617200Y172144D02*
Y177000D01*
G01X618444Y170900D02*
X617200Y172144D01*
G01X607234Y217900D02*
X605484Y219650D01*
G01X631091Y217900D02*
X607234D01*
G01X606778Y216800D02*
X605028Y218550D01*
G01X631547Y216800D02*
X606778D01*
G01X725684Y37754D02*
X620638Y142800D01*
G01X725228Y36654D02*
X620182Y141700D01*
G01X625900Y172000D02*
X635000D01*
G01X625300Y172600D02*
X625900Y172000D01*
G01X625300Y177456D02*
Y172600D01*
G01X624056Y178700D02*
X625300Y177456D01*
G01X621944Y178700D02*
X624056D01*
G01X620700Y177456D02*
X621944Y178700D01*
G01X620700Y172600D02*
Y177456D01*
G01X620100Y172000D02*
X620700Y172600D01*
G01X618900Y172000D02*
X620100D01*
G01X620556Y170900D02*
X618444D01*
G01X621800Y172144D02*
X620556Y170900D01*
G01X621800Y177000D02*
Y172144D01*
G01X622400Y177600D02*
X621800Y177000D01*
G01X623600Y177600D02*
X622400D01*
G01X624200Y177000D02*
X623600Y177600D01*
G01X624200Y172144D02*
Y177000D01*
G01X625444Y170900D02*
X624200Y172144D01*
G01X635456Y170900D02*
X625444D01*
G01X632364Y219173D02*
X631091Y217900D01*
G01X632364Y219866D02*
Y219173D01*
G01X633637Y221139D02*
X632364Y219866D01*
G01X634330Y221139D02*
X633637D01*
G01X655200Y240453D02*
X631547Y216800D01*
G01X643694Y77800D02*
X652656D01*
G01X643238Y76700D02*
X652200D01*
G01X635000Y172000D02*
X648107Y185107D01*
G01X639273Y174717D02*
X635456Y170900D01*
G01X639966Y174717D02*
X639273D01*
G01X641239Y175990D02*
X639966Y174717D01*
G01X641239Y176683D02*
Y175990D01*
G01X642511Y177955D02*
X641239Y176683D01*
G01X643204Y177955D02*
X642511D01*
G01X644477Y179228D02*
X643204Y177955D01*
G01X644477Y179921D02*
Y179228D01*
G01X645750Y181194D02*
X644477Y179921D01*
G01X646443Y181194D02*
X645750D01*
G01X647716Y182467D02*
X646443Y181194D01*
G01X647716Y183160D02*
Y182467D01*
G01X648107Y185107D02*
Y199740D01*
G01X649207Y184651D02*
X647716Y183160D01*
G01X648107Y199740D02*
X680200Y231833D01*
G01X664070Y214147D02*
X649207Y199284D01*
G01X635602Y222411D02*
X634330Y221139D01*
G01X635602Y223104D02*
Y222411D01*
G01X636875Y224377D02*
X635602Y223104D01*
G01X637568Y224377D02*
X636875D01*
G01X638841Y225650D02*
X637568Y224377D01*
G01X638841Y226343D02*
Y225650D01*
G01X640114Y227616D02*
X638841Y226343D01*
G01X640807Y227616D02*
X640114D01*
G01X644384Y231193D02*
X640807Y227616D01*
G01X644384Y231886D02*
Y231193D01*
G01X645657Y233159D02*
X644384Y231886D01*
G01X646350Y233159D02*
X645657D01*
G01X647623Y234432D02*
X646350Y233159D01*
G01X647623Y235125D02*
Y234432D01*
G01X648896Y236398D02*
X647623Y235125D01*
G01X649589Y236398D02*
X648896D01*
G01X648948Y262489D02*
X649993Y261444D01*
G01X661491Y69700D02*
X692091Y39100D01*
G01X651400Y69700D02*
X661491D01*
G01X650800Y70300D02*
X651400Y69700D01*
G01X650800Y71900D02*
Y70300D01*
G01X651400Y72500D02*
X650800Y71900D01*
G01X652656Y72500D02*
X651400D01*
G01X653900Y73744D02*
X652656Y72500D01*
G01X653900Y76556D02*
Y73744D01*
G01X661035Y68600D02*
X691635Y38000D01*
G01X650944Y68600D02*
X661035D01*
G01X649700Y69844D02*
X650944Y68600D01*
G01X649700Y72356D02*
Y69844D01*
G01X650944Y73600D02*
X649700Y72356D01*
G01X652200Y73600D02*
X650944D01*
G01X652800Y74200D02*
X652200Y73600D01*
G01X652800Y76100D02*
Y74200D01*
G01X652656Y77800D02*
X653900Y76556D01*
G01X652200Y76700D02*
X652800Y76100D01*
G01X649207Y199284D02*
Y184651D01*
G01X664763Y214147D02*
X664070D01*
G01X650861Y237670D02*
X649589Y236398D01*
G01X650861Y238363D02*
Y237670D01*
G01X652134Y239636D02*
X650861Y238363D01*
G01X652827Y239636D02*
X652134D01*
G01X654100Y240909D02*
X652827Y239636D01*
G01X654100Y248176D02*
Y240909D01*
G01X655200Y247720D02*
Y240453D01*
G01X655860Y249936D02*
X654100Y248176D01*
G01X655860Y252927D02*
Y249936D01*
G01X649993Y258794D02*
X655860Y252927D01*
G01X649993Y261444D02*
Y258794D01*
G01X656960Y249480D02*
X655200Y247720D01*
G01X656960Y253383D02*
Y249480D01*
G01X651093Y259250D02*
X656960Y253383D01*
G01X651093Y261349D02*
Y259250D01*
G01X652233Y262489D02*
X651093Y261349D01*
G01X666036Y215420D02*
X664763Y214147D01*
G01X666036Y216113D02*
Y215420D01*
G01X667309Y217386D02*
X666036Y216113D01*
G01X668002Y217386D02*
X667309D01*
G01X669275Y218659D02*
X668002Y217386D01*
G01X669275Y219352D02*
Y218659D01*
G01X670547Y220624D02*
X669275Y219352D01*
G01X671240Y220624D02*
X670547D01*
G01X672513Y221897D02*
X671240Y220624D01*
G01X672513Y222590D02*
Y221897D01*
G01X681300Y231377D02*
X672513Y222590D01*
G01X679130Y257970D02*
X677206Y259894D01*
G01X679130Y250814D02*
Y257970D01*
G01X680200Y249744D02*
X679130Y250814D01*
G01X678306Y260350D02*
X680230Y258426D01*
G01X677206Y261396D02*
X676113Y262489D01*
G01X677206Y259894D02*
Y261396D01*
G01X678306Y261397D02*
Y260350D01*
G01X679398Y262489D02*
X678306Y261397D01*
G01X695046Y22853D02*
X695029D01*
G01X696000Y23807D02*
X695046Y22853D01*
G01X695400Y25551D02*
X696000Y24951D01*
G01X695400Y36744D02*
Y25551D01*
G01X694600Y39100D02*
X696500Y37200D01*
G01X692091Y39100D02*
X694600D01*
G01X694144Y38000D02*
X695400Y36744D01*
G01X691635Y38000D02*
X694144D01*
G01X680200Y231833D02*
Y249744D01*
G01X681300Y250200D02*
Y231377D01*
G01X680230Y251270D02*
X681300Y250200D01*
G01X680230Y258426D02*
Y251270D01*
G01X698248Y22855D02*
X698277D01*
G01X697100Y24003D02*
X698248Y22855D01*
G01X697100Y25407D02*
Y24003D01*
G01X696500Y26007D02*
X697100Y25407D01*
G01X696500Y37200D02*
Y26007D01*
G01X696000Y24951D02*
Y23807D01*
G01X726709Y37754D02*
X725684D01*
G01X726253Y36654D02*
X725228D01*
G01X733900Y29007D02*
X726253Y36654D01*
G01X735000Y24698D02*
Y29463D01*
G01X736091Y23607D02*
X735000Y24698D01*
G01X733900Y27807D02*
Y29007D01*
G01X733200Y27107D02*
X733900Y27807D01*
G01X733200Y26207D02*
Y27107D01*
G01X733900Y25507D02*
X733200Y26207D01*
G01X733900Y24701D02*
Y25507D01*
G01X732806Y23607D02*
X733900Y24701D01*
G01X735000Y29463D02*
X726709Y37754D01*
G54D12*
G01X87550Y55550D02*
X88700Y54400D01*
G01X87550Y62911D02*
Y55550D01*
G01X86250Y55350D02*
X85300Y54400D01*
G01X86250Y63450D02*
Y55350D01*
G01X91908Y67269D02*
X87550Y62911D01*
G01X100873Y67269D02*
X91908D01*
G01X91369Y68569D02*
X86250Y63450D01*
G01X100334Y68569D02*
X91369D01*
G01X80200Y62064D02*
X79115Y60979D01*
G01X80200Y64239D02*
Y62064D01*
G01X88280Y72319D02*
X80200Y64239D01*
G01X98080Y72319D02*
X88280D01*
G01X81500Y62364D02*
X82885Y60979D01*
G01X81500Y63700D02*
Y62364D01*
G01X82881Y65081D02*
X81500Y63700D01*
G01X84069Y65081D02*
X82881D01*
G01X85023Y66035D02*
X84069Y65081D01*
G01X85023Y67223D02*
Y66035D01*
G01X88819Y71019D02*
X85023Y67223D01*
G01X98619Y71019D02*
X88819D01*
G01X102500Y55350D02*
Y61700D01*
G01X103450Y54400D02*
X102500Y55350D01*
G01X101200Y55550D02*
Y62239D01*
G01X100050Y54400D02*
X101200Y55550D01*
G01X109098Y68298D02*
X110053Y69253D01*
G01X109098Y67110D02*
Y68298D01*
G01X108144Y66156D02*
X109098Y67110D01*
G01X106956Y66156D02*
X108144D01*
G01X106001Y65201D02*
X106956Y66156D01*
G01X106001Y64013D02*
Y65201D01*
G01X105047Y63059D02*
X106001Y64013D01*
G01X103859Y63059D02*
X105047D01*
G01X102500Y61700D02*
X103859Y63059D01*
G01X101200Y62239D02*
X112811Y73850D01*
G01X124788Y91184D02*
X100873Y67269D01*
G01X133001Y101236D02*
X100334Y68569D01*
G01X129250Y103489D02*
X98080Y72319D01*
G01X130550Y102950D02*
X98619Y71019D01*
G01X118150Y58450D02*
X119200Y57400D01*
G01X118150Y64911D02*
Y58450D01*
G01X116850D02*
X115800Y57400D01*
G01X116850Y65450D02*
Y58450D01*
G01X121539Y68300D02*
X118150Y64911D01*
G01X126343Y68300D02*
X121539D01*
G01X121000Y69600D02*
X116850Y65450D01*
G01X125804Y69600D02*
X121000D01*
G01X125153Y72550D02*
X144300Y91697D01*
G01X113350Y72550D02*
X125153D01*
G01X112195Y71395D02*
X113350Y72550D01*
G01X112195Y70207D02*
Y71395D01*
G01X111241Y69253D02*
X112195Y70207D01*
G01X110053Y69253D02*
X111241D01*
G01X124614Y73850D02*
X143000Y92236D01*
G01X112811Y73850D02*
X124614D01*
G01X125975Y91184D02*
X124788D01*
G01X133800Y58600D02*
X135000Y57400D01*
G01X133800Y68561D02*
Y58600D01*
G01X132500Y58300D02*
X131600Y57400D01*
G01X132500Y69100D02*
Y58300D01*
G01X134755Y69516D02*
X133800Y68561D01*
G01X135943Y69516D02*
X134755D01*
G01X136897Y70470D02*
X135943Y69516D01*
G01X136897Y71658D02*
Y70470D01*
G01X137852Y72613D02*
X136897Y71658D01*
G01X139040Y72613D02*
X137852D01*
G01X139994Y73567D02*
X139040Y72613D01*
G01X139994Y74755D02*
Y73567D01*
G01X158350Y94950D02*
X132500Y69100D01*
G01X140759Y82716D02*
X126343Y68300D01*
G01X160602Y104398D02*
X125804Y69600D01*
G01X140949Y75710D02*
X139994Y74755D01*
G01X140685Y97400D02*
X141985Y98700D01*
G01X141285Y95600D02*
X140685Y96200D01*
G01X139385Y97939D02*
X141446Y100000D01*
G01X139385Y95661D02*
Y97939D01*
G01X140746Y94300D02*
X139385Y95661D01*
G01X126930Y92138D02*
X125975Y91184D01*
G01X126930Y93326D02*
Y92138D01*
G01X127885Y94281D02*
X126930Y93326D01*
G01X129073Y94281D02*
X127885D01*
G01X130027Y95235D02*
X129073Y94281D01*
G01X130027Y96423D02*
Y95235D01*
G01X134301Y100697D02*
X130027Y96423D01*
G01X134301Y113301D02*
Y100697D01*
G01X133001Y113840D02*
Y101236D01*
G01X129250Y115393D02*
Y103489D01*
G01X130550Y114854D02*
Y102950D01*
G01X140685Y113146D02*
X143739Y116200D01*
G01X141339Y107300D02*
X140685Y107954D01*
G01X139385Y113685D02*
X143200Y117500D01*
G01X139385Y107415D02*
Y113685D01*
G01X140800Y106000D02*
X139385Y107415D01*
G01X138845Y117845D02*
X134301Y113301D01*
G01X140033Y117845D02*
X138845D01*
G01X140987Y118799D02*
X140033Y117845D01*
G01X145061Y125900D02*
X133001Y113840D01*
G01X143507Y129650D02*
X129250Y115393D01*
G01X144046Y128350D02*
X130550Y114854D01*
G01X149650Y55465D02*
X150715Y54400D01*
G01X149650Y57550D02*
Y55465D01*
G01X164300Y72200D02*
X149650Y57550D01*
G01X148350Y55435D02*
X147315Y54400D01*
G01X148350Y58089D02*
Y55435D01*
G01X163761Y73500D02*
X148350Y58089D01*
G01X156525Y47375D02*
X155290Y48610D01*
G01X142137Y75710D02*
X140949D01*
G01X143091Y76664D02*
X142137Y75710D01*
G01X143091Y77852D02*
Y76664D01*
G01X152695Y87456D02*
X143091Y77852D01*
G01X153883Y87456D02*
X152695D01*
G01X154837Y88410D02*
X153883Y87456D01*
G01X154837Y89598D02*
Y88410D01*
G01X155792Y90553D02*
X154837Y89598D01*
G01X141947Y82716D02*
X140759D01*
G01X142901Y83670D02*
X141947Y82716D01*
G01X142901Y84858D02*
Y83670D01*
G01X143856Y85813D02*
X142901Y84858D01*
G01X145044Y85813D02*
X143856D01*
G01X145998Y86767D02*
X145044Y85813D01*
G01X145998Y87955D02*
Y86767D01*
G01X146953Y88910D02*
X145998Y87955D01*
G01X148141Y88910D02*
X146953D01*
G01X149095Y89864D02*
X148141Y88910D01*
G01X149095Y91052D02*
Y89864D01*
G01X156980Y90553D02*
X155792D01*
G01X158805Y100762D02*
X149095Y91052D01*
G01X146900Y104939D02*
X144539Y107300D01*
G01X146900Y100361D02*
Y104939D01*
G01X145239Y98700D02*
X146900Y100361D01*
G01X141985Y98700D02*
X145239D01*
G01X140685Y96200D02*
Y97400D01*
G01X142739Y95600D02*
X141285D01*
G01X144300Y94039D02*
X142739Y95600D01*
G01X144300Y91697D02*
Y94039D01*
G01X145600Y104400D02*
X144000Y106000D01*
G01X145600Y100900D02*
Y104400D01*
G01X144700Y100000D02*
X145600Y100900D01*
G01X141446Y100000D02*
X144700D01*
G01X142200Y94300D02*
X140746D01*
G01X143000Y93500D02*
X142200Y94300D01*
G01X143000Y92236D02*
Y93500D01*
G01X154740Y120240D02*
X158200Y123700D01*
G01X154740Y111320D02*
Y120240D01*
G01X151220Y107800D02*
X154740Y111320D01*
G01X148361Y107800D02*
X151220D01*
G01X146900Y109261D02*
X148361Y107800D01*
G01X146900Y114961D02*
Y109261D01*
G01X145661Y116200D02*
X146900Y114961D01*
G01X143739Y116200D02*
X145661D01*
G01X140685Y107954D02*
Y113146D01*
G01X144539Y107300D02*
X141339D01*
G01X153440Y120779D02*
X156900Y124239D01*
G01X153440Y111859D02*
Y120779D01*
G01X150681Y109100D02*
X153440Y111859D01*
G01X148900Y109100D02*
X150681D01*
G01X148200Y109800D02*
X148900Y109100D01*
G01X148200Y115500D02*
Y109800D01*
G01X146200Y117500D02*
X148200Y115500D01*
G01X143200Y117500D02*
X146200D01*
G01X144000Y106000D02*
X140800D01*
G01X140987Y119987D02*
Y118799D01*
G01X141942Y120942D02*
X140987Y119987D01*
G01X144084Y121896D02*
X143130Y120942D01*
G01D02*
X141942D01*
G01X144084Y123084D02*
Y121896D01*
G01X145600Y124600D02*
X144084Y123084D01*
G01X150600Y124600D02*
X145600D01*
G01X154982Y128982D02*
X150600Y124600D01*
G01X156170Y128982D02*
X154982D01*
G01X150061Y125900D02*
X145061D01*
G01X171845Y147684D02*
X150061Y125900D01*
G01X148507Y129650D02*
X143507D01*
G01X168095Y149238D02*
X148507Y129650D01*
G01X149046Y128350D02*
X144046D01*
G01X169395Y148699D02*
X149046Y128350D01*
G01X167450Y35550D02*
X319550D01*
G01X165500Y37500D02*
X167450Y35550D01*
G01X165500Y38939D02*
Y37500D01*
G01X157825Y46614D02*
X165500Y38939D01*
G01X164200Y38400D02*
X156525Y46075D01*
G01X164200Y36961D02*
Y38400D01*
G01X166911Y34250D02*
X164200Y36961D01*
G01X212635Y34250D02*
X166911D01*
G01X165400Y55463D02*
X166463Y54400D01*
G01X165400Y61261D02*
Y55463D01*
G01X169700Y58000D02*
Y61000D01*
G01X171800Y55900D02*
X169700Y58000D01*
G01X164100Y55437D02*
X163063Y54400D01*
G01X164100Y61800D02*
Y55437D01*
G01X171000Y58539D02*
Y61539D01*
G01X172339Y57200D02*
X171000Y58539D01*
G01X157825Y47375D02*
Y46614D01*
G01X159060Y48610D02*
X157825Y47375D01*
G01X156525Y46075D02*
Y47375D01*
G01X170290Y49600D02*
X171525Y48365D01*
G01X166499Y62360D02*
X165400Y61261D01*
G01X168340Y62360D02*
X166499D01*
G01X169700Y61000D02*
X168340Y62360D01*
G01X165960Y63660D02*
X164100Y61800D01*
G01X168879Y63660D02*
X165960D01*
G01X171000Y61539D02*
X168879Y63660D01*
G01X183214Y72200D02*
X164300D01*
G01X182675Y73500D02*
X163761D01*
G01X157934Y91507D02*
X156980Y90553D01*
G01X157934Y92695D02*
Y91507D01*
G01X158889Y93650D02*
X157934Y92695D01*
G01X159400Y93650D02*
X158889D01*
G01X164106Y98356D02*
X159400Y93650D01*
G01X165294Y98356D02*
X164106D01*
G01X166248Y99310D02*
X165294Y98356D01*
G01X166248Y100498D02*
Y99310D01*
G01X167203Y101453D02*
X166248Y100498D01*
G01X168391Y101453D02*
X167203D01*
G01X169345Y102407D02*
X168391Y101453D01*
G01X169345Y103595D02*
Y102407D01*
G01X170300Y104550D02*
X169345Y103595D01*
G01X170300Y111927D02*
Y104550D01*
G01X158861Y94950D02*
X158350D01*
G01X169000Y105089D02*
X158861Y94950D01*
G01X169000Y112466D02*
Y105089D01*
G01X159993Y100762D02*
X158805D01*
G01X160947Y101716D02*
X159993Y100762D01*
G01X160947Y102904D02*
Y101716D01*
G01X161902Y103859D02*
X160947Y102904D01*
G01X161902Y109578D02*
Y103859D01*
G01X160602Y120689D02*
Y104398D01*
G01X173859Y115486D02*
X170300Y111927D01*
G01X193500Y136966D02*
X169000Y112466D01*
G01X162742Y110418D02*
X161902Y109578D01*
G01X162742Y111768D02*
Y110418D01*
G01X161902Y112608D02*
X162742Y111768D01*
G01X161902Y113958D02*
Y112608D01*
G01X162742Y114798D02*
X161902Y113958D01*
G01X162742Y116148D02*
Y114798D01*
G01X161902Y116988D02*
X162742Y116148D01*
G01X161902Y120150D02*
Y116988D01*
G01X164561Y122809D02*
X161902Y120150D01*
G01X172206Y132293D02*
X160602Y120689D01*
G01X165749Y122809D02*
X164561D01*
G01X166703Y123763D02*
X165749Y122809D01*
G01X166703Y124951D02*
Y123763D01*
G01X167658Y125906D02*
X166703Y124951D01*
G01X168846Y125906D02*
X167658D01*
G01X169800Y126860D02*
X168846Y125906D01*
G01X169800Y128048D02*
Y126860D01*
G01X170755Y129003D02*
X169800Y128048D01*
G01X171943Y129003D02*
X170755D01*
G01X167940Y135048D02*
X172442Y139550D01*
G01X167940Y133860D02*
Y135048D01*
G01X166985Y132905D02*
X167940Y133860D01*
G01X165797Y132905D02*
X166985D01*
G01X164843Y131951D02*
X165797Y132905D01*
G01X164843Y130763D02*
Y131951D01*
G01X163888Y129808D02*
X164843Y130763D01*
G01X162700Y129808D02*
X163888D01*
G01X161746Y128854D02*
X162700Y129808D01*
G01X161746Y127666D02*
Y128854D01*
G01X160791Y126711D02*
X161746Y127666D01*
G01X159603Y126711D02*
X160791D01*
G01X158200Y125308D02*
X159603Y126711D01*
G01X158200Y123700D02*
Y125308D01*
G01X156900Y125847D02*
X171903Y140850D01*
G01X156900Y124239D02*
Y125847D01*
G01X157124Y129936D02*
X156170Y128982D01*
G01X157124Y131124D02*
Y129936D01*
G01X159073Y133073D02*
X157124Y131124D01*
G01X160261Y133073D02*
X159073D01*
G01X161215Y134027D02*
X160261Y133073D01*
G01X161215Y135215D02*
Y134027D01*
G01X165428Y139428D02*
X161215Y135215D01*
G01X166615Y139428D02*
X165428D01*
G01X167570Y140382D02*
X166615Y139428D01*
G01X167570Y141570D02*
Y140382D01*
G01X173145Y147145D02*
X167570Y141570D01*
G01X168095Y152338D02*
Y149238D01*
G01X169395Y151799D02*
Y148699D01*
G01X177532Y161775D02*
X168095Y152338D01*
G01X178071Y160475D02*
X169395Y151799D01*
G01X176938Y43600D02*
X224339D01*
G01X172825Y47713D02*
X176938Y43600D01*
G01X176399Y42300D02*
X223800D01*
G01X171525Y47174D02*
X176399Y42300D01*
G01X183000Y58000D02*
X207500D01*
G01X181150Y56150D02*
X183000Y58000D01*
G01X181150Y55050D02*
Y56150D01*
G01X181800Y54400D02*
X181150Y55050D01*
G01X179850Y55250D02*
X179000Y54400D01*
G01X179850Y56689D02*
Y55250D01*
G01X182461Y59300D02*
X179850Y56689D01*
G01X174718Y55900D02*
X171800D01*
G01X176339Y57521D02*
X174718Y55900D01*
G01X176339Y60900D02*
Y57521D01*
G01X174179Y57200D02*
X172339D01*
G01X175039Y58060D02*
X174179Y57200D01*
G01X175039Y61439D02*
Y58060D01*
G01X186865Y54300D02*
X187800Y53365D01*
G01X172825Y48365D02*
Y47713D01*
G01X174060Y49600D02*
X172825Y48365D01*
G01X171525D02*
Y47174D01*
G01X206961Y59300D02*
X182461D01*
G01X177539Y62100D02*
X176339Y60900D01*
G01X179140Y62100D02*
X177539D01*
G01X179490Y61750D02*
X179140Y62100D01*
G01X185689Y61750D02*
X179490D01*
G01X187459Y63520D02*
X185689Y61750D01*
G01X177000Y63400D02*
X175039Y61439D01*
G01X179679Y63400D02*
X177000D01*
G01X180029Y63050D02*
X179679Y63400D01*
G01X185150Y63050D02*
X180029D01*
G01X186159Y64059D02*
X185150Y63050D01*
G01X186159Y69180D02*
Y64059D01*
G01X189770Y72791D02*
X186159Y69180D01*
G01X184867Y73853D02*
X183214Y72200D01*
G01X186055Y73853D02*
X184867D01*
G01X187009Y74807D02*
X186055Y73853D01*
G01X187425Y78250D02*
X182675Y73500D01*
G01X175047Y115486D02*
X173859D01*
G01X176002Y116441D02*
X175047Y115486D01*
G01X176002Y117629D02*
Y116441D01*
G01X176956Y118583D02*
X176002Y117629D01*
G01X178144Y118583D02*
X176956D01*
G01X179099Y119538D02*
X178144Y118583D01*
G01X179099Y120726D02*
Y119538D01*
G01X180054Y121681D02*
X179099Y120726D01*
G01X181242Y121681D02*
X180054D01*
G01X182196Y122635D02*
X181242Y121681D01*
G01X182196Y123823D02*
Y122635D01*
G01X191404Y133031D02*
X182196Y123823D01*
G01X172897Y129957D02*
X171943Y129003D01*
G01X172897Y131145D02*
Y129957D01*
G01X173506Y131754D02*
X172897Y131145D01*
G01X173506Y134167D02*
Y131754D01*
G01X174219Y134880D02*
X173506Y134167D01*
G01X175720Y134880D02*
X174219D01*
G01X179950Y130650D02*
X175720Y134880D01*
G01X183550Y130650D02*
X179950D01*
G01X185100Y132200D02*
X183550Y130650D01*
G01X185100Y134639D02*
Y132200D01*
G01X182600Y137139D02*
X185100Y134639D01*
G01X172206Y134706D02*
Y132293D01*
G01X173680Y136180D02*
X172206Y134706D01*
G01X176259Y136180D02*
X173680D01*
G01X180489Y131950D02*
X176259Y136180D01*
G01X183011Y131950D02*
X180489D01*
G01X183800Y132739D02*
X183011Y131950D01*
G01X183800Y134100D02*
Y132739D01*
G01X181300Y136600D02*
X183800Y134100D01*
G01X182600Y139307D02*
Y137139D01*
G01X183716Y140423D02*
X182600Y139307D01*
G01X185059Y140423D02*
X183716D01*
G01X186202Y139280D02*
X185059Y140423D01*
G01X188676Y139280D02*
X186202D01*
G01X181300Y139846D02*
Y136600D01*
G01X183177Y141723D02*
X181300Y139846D01*
G01X185598Y141723D02*
X183177D01*
G01X186741Y140580D02*
X185598Y141723D01*
G01X188137Y140580D02*
X186741D01*
G01X185408Y147419D02*
X189319D01*
G01X184450Y146461D02*
X185408Y147419D01*
G01X184450Y145274D02*
Y146461D01*
G01X183496Y144319D02*
X184450Y145274D01*
G01X182308Y144319D02*
X183496D01*
G01X177539Y139550D02*
X182308Y144319D01*
G01X172442Y139550D02*
X177539D01*
G01X184869Y148719D02*
X188780D01*
G01X177000Y140850D02*
X184869Y148719D01*
G01X171903Y140850D02*
X177000D01*
G01X173145Y148745D02*
Y147145D01*
G01X177500Y153100D02*
X173145Y148745D01*
G01X171845Y149284D02*
Y147684D01*
G01X176961Y154400D02*
X171845Y149284D01*
G01X189696Y153100D02*
X177500D01*
G01X189157Y154400D02*
X176961D01*
G01X181670Y161775D02*
X177532D01*
G01X191447Y171552D02*
X181670Y161775D01*
G01X182209Y160475D02*
X178071D01*
G01X192747Y171013D02*
X182209Y160475D01*
G01X189100Y53700D02*
X189700Y54300D01*
G01X189100Y50300D02*
Y53700D01*
G01X192300Y47100D02*
X189100Y50300D01*
G01X233739Y47100D02*
X192300D01*
G01X191761Y45800D02*
X233200D01*
G01X187800Y49761D02*
X191761Y45800D01*
G01X187800Y53365D02*
Y49761D01*
G01X187459Y68641D02*
Y63520D01*
G01X190309Y71491D02*
X187459Y68641D01*
G01X198701Y71491D02*
X190309D01*
G01X202753Y75543D02*
X198701Y71491D01*
G01X198162Y72791D02*
X189770D01*
G01X208150Y82779D02*
X198162Y72791D01*
G01X187009Y75995D02*
Y74807D01*
G01X187964Y76950D02*
X187009Y75995D01*
G01X198856Y76950D02*
X187964D01*
G01X205650Y83744D02*
X198856Y76950D01*
G01X198317Y78250D02*
X187425D01*
G01X204350Y84283D02*
X198317Y78250D01*
G01X196610Y81595D02*
X197845Y80360D01*
G01X196610Y86353D02*
Y81595D01*
G01X197450Y87193D02*
X196610Y86353D01*
G01X197450Y88543D02*
Y87193D01*
G01X196610Y89383D02*
X197450Y88543D01*
G01X196610Y91310D02*
Y89383D01*
G01X195310Y81595D02*
Y91849D01*
G01X194075Y80360D02*
X195310Y81595D01*
G01X199427Y94127D02*
X196610Y91310D01*
G01X199427Y95477D02*
Y94127D01*
G01X200267Y96317D02*
X199427Y95477D01*
G01X200267Y97667D02*
Y96317D01*
G01X199427Y98507D02*
X200267Y97667D01*
G01X199427Y99857D02*
Y98507D01*
G01X200267Y100697D02*
X199427Y99857D01*
G01X200267Y102047D02*
Y100697D01*
G01X199427Y102887D02*
X200267Y102047D01*
G01X199427Y104237D02*
Y102887D01*
G01X200267Y105077D02*
X199427Y104237D01*
G01X200267Y106427D02*
Y105077D01*
G01X198127Y94666D02*
Y139962D01*
G01X195310Y91849D02*
X198127Y94666D01*
G01X199427Y107267D02*
X200267Y106427D01*
G01X199427Y114127D02*
Y107267D01*
G01X200267Y114967D02*
X199427Y114127D01*
G01X200267Y116317D02*
Y114967D01*
G01X199427Y117157D02*
X200267Y116317D01*
G01X199427Y118507D02*
Y117157D01*
G01X200267Y119347D02*
X199427Y118507D01*
G01X200267Y120697D02*
Y119347D01*
G01X199427Y121537D02*
X200267Y120697D01*
G01X192592Y133031D02*
X191404D01*
G01X193546Y133985D02*
X192592Y133031D01*
G01X193546Y135173D02*
Y133985D01*
G01X194800Y136427D02*
X193546Y135173D01*
G01X199427Y122887D02*
Y121537D01*
G01X200267Y123727D02*
X199427Y122887D01*
G01X200267Y125077D02*
Y123727D01*
G01X199427Y125917D02*
X200267Y125077D01*
G01X199427Y127267D02*
Y125917D01*
G01X200267Y128107D02*
X199427Y127267D01*
G01X200267Y129457D02*
Y128107D01*
G01X199427Y130297D02*
X200267Y129457D01*
G01X199427Y139423D02*
Y130297D01*
G01X194800Y140100D02*
Y136427D01*
G01X199913Y145213D02*
X194800Y140100D01*
G01X213648Y145213D02*
X199913D01*
G01X193500Y140639D02*
Y136966D01*
G01X199374Y146513D02*
X193500Y140639D01*
G01X213109Y146513D02*
X199374D01*
G01X190128Y140732D02*
X188676Y139280D01*
G01X190128Y142797D02*
Y140732D01*
G01X191000Y143669D02*
X190128Y142797D01*
G01X193065Y143669D02*
X191000D01*
G01X198359Y148963D02*
X193065Y143669D01*
G01X200602Y148963D02*
X198359D01*
G01X202239Y150600D02*
X200602Y148963D01*
G01X188828Y141271D02*
X188137Y140580D01*
G01X188828Y143336D02*
Y141271D01*
G01X190461Y144969D02*
X188828Y143336D01*
G01X192526Y144969D02*
X190461D01*
G01X197820Y150263D02*
X192526Y144969D01*
G01X200063Y150263D02*
X197820D01*
G01X201700Y151900D02*
X200063Y150263D01*
G01X189319Y147419D02*
X198000Y156100D01*
G01X188780Y148719D02*
X197461Y157400D01*
G01X201467Y141463D02*
X199427Y139423D01*
G01X202817Y141463D02*
X201467D01*
G01X200928Y142763D02*
X208037D01*
G01X198127Y139962D02*
X200928Y142763D01*
G01X203900Y151900D02*
X201700D01*
G01X202100Y156100D02*
X205209Y159209D01*
G01X198000Y156100D02*
X202100D01*
G01X201561Y157400D02*
X212580Y168419D01*
G01X197461Y157400D02*
X201561D01*
G01X197078Y160482D02*
X189696Y153100D01*
G01X197078Y165659D02*
Y160482D01*
G01X214786Y183367D02*
X197078Y165659D01*
G01X195778Y161021D02*
X189157Y154400D01*
G01X195778Y166198D02*
Y161021D01*
G01X213486Y183906D02*
X195778Y166198D01*
G01X191447Y173186D02*
Y171552D01*
G01X199347Y181086D02*
X191447Y173186D01*
G01X205361Y181086D02*
X199347D01*
G01X192747Y172647D02*
Y171013D01*
G01X199886Y179786D02*
X192747Y172647D01*
G01X205900Y179786D02*
X199886D01*
G01X213475Y33410D02*
X212635Y34250D01*
G01X214825Y33410D02*
X213475D01*
G01X215665Y34250D02*
X214825Y33410D01*
G01X217015Y34250D02*
X215665D01*
G01X217855Y33410D02*
X217015Y34250D01*
G01X207500Y58000D02*
X211850Y62350D01*
G01X211311Y63650D02*
X206961Y59300D01*
G01X215189Y62350D02*
X220400Y67561D01*
G01X211850Y62350D02*
X215189D01*
G01X214650Y63650D02*
X211311D01*
G01X219100Y68100D02*
X214650Y63650D01*
G01X203941Y75543D02*
X202753D01*
G01X204895Y76497D02*
X203941Y75543D01*
G01X204895Y77685D02*
Y76497D01*
G01X209450Y82240D02*
X204895Y77685D01*
G01X209450Y83606D02*
Y82240D01*
G01X210290Y84446D02*
X209450Y83606D01*
G01X210290Y85796D02*
Y84446D01*
G01X209450Y86636D02*
X210290Y85796D01*
G01X209450Y87986D02*
Y86636D01*
G01X210290Y88826D02*
X209450Y87986D01*
G01X210290Y90176D02*
Y88826D01*
G01X208150Y98077D02*
Y82779D01*
G01X205650Y99042D02*
Y83744D01*
G01X204350Y99581D02*
Y84283D01*
G01X209450Y91016D02*
X210290Y90176D01*
G01X209450Y92366D02*
Y91016D01*
G01X210290Y93206D02*
X209450Y92366D01*
G01X210290Y94556D02*
Y93206D01*
G01X209450Y95396D02*
X210290Y94556D01*
G01X209450Y97538D02*
Y95396D01*
G01X212415Y100503D02*
X209450Y97538D01*
G01X213603Y100503D02*
X212415D01*
G01X214558Y101458D02*
X213603Y100503D01*
G01X214558Y102646D02*
Y101458D01*
G01X215512Y103600D02*
X214558Y102646D01*
G01X216700Y103600D02*
X215512D01*
G01X217655Y104555D02*
X216700Y103600D01*
G01X216913Y106840D02*
X208150Y98077D01*
G01X214180Y107572D02*
X205650Y99042D01*
G01X212880Y108111D02*
X204350Y99581D01*
G01X218213Y106301D02*
X217655Y105743D01*
G01X216913Y134986D02*
Y106840D01*
G01X214180Y140441D02*
Y107572D01*
G01X212880Y140980D02*
Y108111D01*
G01X232325Y150398D02*
X216913Y134986D01*
G01X221452Y153017D02*
X213648Y145213D01*
G01X220152Y153556D02*
X213109Y146513D01*
G01X225202Y151463D02*
X214180Y140441D01*
G01X223902Y152002D02*
X212880Y140980D01*
G01X203361Y150600D02*
X202239D01*
G01X204261Y149700D02*
X203361Y150600D01*
G01X212831Y149700D02*
X204261D01*
G01X217630Y154499D02*
X212831Y149700D01*
G01X204800Y151000D02*
X203900Y151900D01*
G01X212292Y151000D02*
X204800D01*
G01X216330Y155038D02*
X212292Y151000D01*
G01X203657Y140623D02*
X202817Y141463D01*
G01X205007Y140623D02*
X203657D01*
G01X205847Y141463D02*
X205007Y140623D01*
G01X207498Y141463D02*
X205847D01*
G01X208024Y140937D02*
X207498Y141463D01*
G01X208024Y140274D02*
Y140937D01*
G01X206790Y139040D02*
X208024Y140274D01*
G01X209324Y140251D02*
X210547Y139028D01*
G01X209324Y141476D02*
Y140251D01*
G01X208037Y142763D02*
X209324Y141476D01*
G01X217630Y173487D02*
Y154499D01*
G01X216330Y174026D02*
Y155038D01*
G01X210449Y164449D02*
X213880Y167880D01*
G01X210449Y163261D02*
Y164449D01*
G01X209494Y162306D02*
X210449Y163261D01*
G01X208306Y162306D02*
X209494D01*
G01X207352Y161352D02*
X208306Y162306D01*
G01X207352Y160164D02*
Y161352D01*
G01X206397Y159209D02*
X207352Y160164D01*
G01X205209Y159209D02*
X206397D01*
G01X222336Y178193D02*
X217630Y173487D01*
G01X221036Y178732D02*
X216330Y174026D01*
G01X213880Y175041D02*
X218586Y179747D01*
G01X213880Y167880D02*
Y175041D01*
G01X217286Y180286D02*
Y188093D01*
G01X212580Y175580D02*
X217286Y180286D01*
G01X212580Y168419D02*
Y175580D01*
G01X209736Y185461D02*
X205361Y181086D01*
G01X211036Y184922D02*
X205900Y179786D01*
G01X217286Y188093D02*
X231361Y202168D01*
G01X214786Y189058D02*
Y183367D01*
G01X235112Y209384D02*
X214786Y189058D01*
G01X213486Y189597D02*
Y183906D01*
G01X247339Y223450D02*
X213486Y189597D01*
G01X209736Y193775D02*
Y185461D01*
G01X213536Y197575D02*
X209736Y193775D01*
G01X216160Y197575D02*
X213536D01*
G01X245785Y227200D02*
X216160Y197575D01*
G01X211036Y193236D02*
Y184922D01*
G01X214075Y196275D02*
X211036Y193236D01*
G01X216699Y196275D02*
X214075D01*
G01X246324Y225900D02*
X216699Y196275D01*
G01X219205Y33410D02*
X217855D01*
G01X220045Y34250D02*
X219205Y33410D01*
G01X221395Y34250D02*
X220045D01*
G01X222235Y33410D02*
X221395Y34250D01*
G01X223585Y33410D02*
X222235D01*
G01X224425Y34250D02*
X223585Y33410D01*
G01X320089Y34250D02*
X224425D01*
G01X233751Y44217D02*
X232591Y43057D01*
G01X227139Y40800D02*
X237000D01*
G01X224339Y43600D02*
X227139Y40800D01*
G01X226600Y39500D02*
X237539D01*
G01X223800Y42300D02*
X226600Y39500D01*
G01X228100Y72000D02*
Y76100D01*
G01X226700Y70600D02*
X228100Y72000D01*
G01X221300Y70600D02*
X226700D01*
G01X220400Y69700D02*
X221300Y70600D01*
G01X220400Y67561D02*
Y69700D01*
G01X219100Y70239D02*
Y68100D01*
G01X220761Y71900D02*
X219100Y70239D01*
G01X226161Y71900D02*
X220761D01*
G01X226800Y72539D02*
X226161Y71900D01*
G01X226800Y75561D02*
Y72539D01*
G01X230350Y85950D02*
X233100Y88700D01*
G01X226650Y85950D02*
X230350D01*
G01X225000Y84300D02*
X226650Y85950D01*
G01X225000Y79200D02*
Y84300D01*
G01X228100Y76100D02*
X225000Y79200D01*
G01X223700Y78661D02*
X226800Y75561D01*
G01X223700Y84839D02*
Y78661D01*
G01X226111Y87250D02*
X223700Y84839D01*
G01X229811Y87250D02*
X226111D01*
G01X231800Y89239D02*
X229811Y87250D01*
G01X231800Y90311D02*
Y89239D01*
G01X230650Y95940D02*
X238725Y104015D01*
G01X230650Y93300D02*
Y95940D01*
G01X233100Y90850D02*
X230650Y93300D01*
G01X229350Y92761D02*
X231800Y90311D01*
G01X229350Y96479D02*
Y92761D01*
G01X237425Y104554D02*
X229350Y96479D01*
G01X217655Y105743D02*
Y104555D01*
G01X232000Y114925D02*
X237425Y109500D01*
G01X232000Y130652D02*
Y114925D01*
G01X218213Y134447D02*
Y106301D01*
G01X237348Y136000D02*
X232000Y130652D01*
G01X233625Y149859D02*
X218213Y134447D01*
G01X232325Y163247D02*
Y150398D01*
G01X225202Y170451D02*
Y151463D01*
G01X240700Y171622D02*
X232325Y163247D01*
G01X221452Y172005D02*
Y153017D01*
G01X220152Y172544D02*
Y153556D01*
G01X223902Y170990D02*
Y152002D01*
G01X226086Y176639D02*
X221452Y172005D01*
G01X226086Y177665D02*
Y176639D01*
G01X227325Y178904D02*
X226086Y177665D01*
G01X227325Y183586D02*
Y178904D01*
G01X224786Y177178D02*
X220152Y172544D01*
G01X224786Y178204D02*
Y177178D01*
G01X226025Y179443D02*
X224786Y178204D01*
G01X226025Y184125D02*
Y179443D01*
G01X229836Y175085D02*
X225202Y170451D01*
G01X229836Y176111D02*
Y175085D01*
G01X231075Y177350D02*
X229836Y176111D01*
G01X231075Y182032D02*
Y177350D01*
G01X236843Y187800D02*
X231075Y182032D01*
G01X228536Y175624D02*
X223902Y170990D01*
G01X228536Y176650D02*
Y175624D01*
G01X229775Y177889D02*
X228536Y176650D01*
G01X229775Y182571D02*
Y177889D01*
G01X236304Y189100D02*
X229775Y182571D01*
G01X222336Y186000D02*
Y178193D01*
G01X221036Y186539D02*
Y178732D01*
G01X218586Y179747D02*
Y187554D01*
G01X237139Y193400D02*
X227325Y183586D01*
G01X236600Y194700D02*
X226025Y184125D01*
G01X223418Y187082D02*
X222336Y186000D01*
G01X225517Y187082D02*
X223418D01*
G01X228768Y190333D02*
X225517Y187082D01*
G01X228768Y192432D02*
Y190333D01*
G01X233313Y196977D02*
X228768Y192432D01*
G01X222879Y188382D02*
X221036Y186539D01*
G01X224978Y188382D02*
X222879D01*
G01X227468Y190872D02*
X224978Y188382D01*
G01X227468Y192971D02*
Y190872D01*
G01X232774Y198277D02*
X227468Y192971D01*
G01X224329Y193297D02*
X231900Y200868D01*
G01X224329Y192109D02*
Y193297D01*
G01X223374Y191154D02*
X224329Y192109D01*
G01X222186Y191154D02*
X223374D01*
G01X218586Y187554D02*
X222186Y191154D01*
G01X234495Y198277D02*
X232774D01*
G01X231900Y200868D02*
X233621D01*
G01X233082Y202168D02*
X242857Y211943D01*
G01X231361Y202168D02*
X233082D01*
G01X236211Y43057D02*
X235051Y44217D01*
G01X244225Y41517D02*
X245385Y40357D01*
G01X244225Y42739D02*
Y41517D01*
G01X242864Y44100D02*
X244225Y42739D01*
G01X237000Y40800D02*
X240300Y44100D01*
G01X242925Y41517D02*
X241765Y40357D01*
G01X242925Y42200D02*
Y41517D01*
G01X242325Y42800D02*
X242925Y42200D01*
G01X240839Y42800D02*
X242325D01*
G01X237539Y39500D02*
X240839Y42800D01*
G01X235051Y45788D02*
X233739Y47100D01*
G01X235051Y44217D02*
Y45788D01*
G01X233751Y45249D02*
Y44217D01*
G01X233200Y45800D02*
X233751Y45249D01*
G01X240300Y44100D02*
X242864D01*
G01X233100Y88700D02*
Y90850D01*
G01X248450Y90511D02*
X263136Y75825D01*
G01X248450Y111197D02*
Y90511D01*
G01X238725Y104015D02*
Y110039D01*
G01X237425Y109500D02*
Y104554D01*
G01X246625Y119249D02*
X252200Y113674D01*
G01X246625Y161039D02*
Y119249D01*
G01X247925Y119788D02*
X253500Y114213D01*
G01X247925Y160500D02*
Y119788D01*
G01X239825Y119822D02*
X248450Y111197D01*
G01X239825Y131379D02*
Y119822D01*
G01X241125Y120361D02*
X249750Y111736D01*
G01X241125Y130840D02*
Y120361D01*
G01X233300Y115464D02*
Y130113D01*
G01X238725Y110039D02*
X233300Y115464D01*
G01X241200Y132754D02*
X239825Y131379D01*
G01X241200Y146961D02*
Y132754D01*
G01X242500Y132215D02*
X241125Y130840D01*
G01X242500Y147500D02*
Y132215D01*
G01X238648Y135461D02*
Y146048D01*
G01X233300Y130113D02*
X238648Y135461D01*
G01X237348Y145509D02*
Y136000D01*
G01X239825Y148336D02*
X241200Y146961D01*
G01X239825Y160139D02*
Y148336D01*
G01X241125Y148875D02*
X242500Y147500D01*
G01X241125Y159600D02*
Y148875D01*
G01X237375Y147321D02*
Y161154D01*
G01X238648Y146048D02*
X237375Y147321D01*
G01X236075Y146782D02*
X237348Y145509D01*
G01X236075Y161693D02*
Y146782D01*
G01X233625Y162708D02*
Y149859D01*
G01X253700Y168114D02*
X246625Y161039D01*
G01X255000Y167575D02*
X247925Y160500D01*
G01X249950Y170264D02*
X239825Y160139D01*
G01X251250Y169725D02*
X241125Y159600D01*
G01X237375Y161154D02*
X245750Y169529D01*
G01X244450Y170068D02*
X236075Y161693D01*
G01X242000Y171083D02*
X233625Y162708D01*
G01X245750Y176196D02*
X251777Y182223D01*
G01X245750Y169529D02*
Y176196D01*
G01X244450Y176735D02*
Y170068D01*
G01X251238Y183523D02*
X244450Y176735D01*
G01X242000Y177750D02*
Y171083D01*
G01X244300Y180050D02*
X242000Y177750D01*
G01X244300Y184000D02*
Y180050D01*
G01X240700Y178289D02*
Y171622D01*
G01X243000Y180589D02*
X240700Y178289D01*
G01X243000Y184539D02*
Y180589D01*
G01X245705Y185405D02*
X244300Y184000D01*
G01X246893Y185405D02*
X245705D01*
G01X247847Y186359D02*
X246893Y185405D01*
G01X247847Y187547D02*
Y186359D01*
G01X248802Y188502D02*
X247847Y187547D01*
G01X258211Y199750D02*
X243000Y184539D01*
G01X242371Y193400D02*
X237139D01*
G01X244450Y195479D02*
X242371Y193400D01*
G01X244450Y198750D02*
Y195479D01*
G01X241832Y194700D02*
X236600D01*
G01X243150Y196018D02*
X241832Y194700D01*
G01X243150Y199289D02*
Y196018D01*
G01X242796Y187800D02*
X236843D01*
G01X257196Y202200D02*
X242796Y187800D01*
G01X242257Y189100D02*
X236304D01*
G01X256657Y203500D02*
X242257Y189100D01*
G01X235034Y196977D02*
X233313D01*
G01X237466Y199409D02*
X235034Y196977D01*
G01X251650Y205950D02*
X244450Y198750D01*
G01X251111Y207250D02*
X243150Y199289D01*
G01X238654Y199409D02*
X237466D01*
G01X239608Y200363D02*
X238654Y199409D01*
G01X239608Y201551D02*
Y200363D01*
G01X240563Y202506D02*
X239608Y201551D01*
G01X241751Y202506D02*
X240563D01*
G01X242705Y203460D02*
X241751Y202506D01*
G01X242705Y204648D02*
Y203460D01*
G01X243660Y205603D02*
X242705Y204648D01*
G01X244848Y205603D02*
X243660D01*
G01X245802Y206557D02*
X244848Y205603D01*
G01X245802Y207745D02*
Y206557D01*
G01X247757Y209700D02*
X245802Y207745D01*
G01X258239Y209700D02*
X247757D01*
G01X247218Y211000D02*
X234495Y198277D01*
G01X257700Y211000D02*
X247218D01*
G01X244157Y213125D02*
X248066Y217034D01*
G01X244157Y211404D02*
Y213125D01*
G01X233621Y200868D02*
X244157Y211404D01*
G01X242857Y211943D02*
Y213664D01*
G01X236300Y209384D02*
X235112D01*
G01X237254Y210338D02*
X236300Y209384D01*
G01X237254Y211526D02*
Y210338D01*
G01X238209Y212481D02*
X237254Y211526D01*
G01X239397Y212481D02*
X238209D01*
G01X240351Y213435D02*
X239397Y212481D01*
G01X248066Y217034D02*
X256777D01*
G01X247527Y218334D02*
X256238D01*
G01X242857Y213664D02*
X247527Y218334D01*
G01X240351Y214623D02*
Y213435D01*
G01X247878Y222150D02*
X240351Y214623D01*
G01X250100Y222150D02*
X247878D01*
G01X256050Y223450D02*
X247339D01*
G01X254400Y227200D02*
X245785D01*
G01X254939Y225900D02*
X246324D01*
G01X252200Y97154D02*
X287800Y61554D01*
G01X253500Y97693D02*
X289100Y62093D01*
G01X263136Y75825D02*
X265475D01*
G01X263675Y77125D02*
X266014D01*
G01X249750Y91050D02*
X263675Y77125D01*
G01X252200Y113674D02*
Y97154D01*
G01X253500Y114213D02*
Y97693D01*
G01X249750Y111736D02*
Y91050D01*
G01X261346Y116800D02*
X265390Y112756D01*
G01X258800Y116800D02*
X261346D01*
G01X256050Y119550D02*
X258800Y116800D01*
G01X256050Y158488D02*
Y119550D01*
G01X261885Y118100D02*
X266690Y113295D01*
G01X259339Y118100D02*
X261885D01*
G01X257350Y120089D02*
X259339Y118100D01*
G01X257350Y157949D02*
Y120089D01*
G01X262714Y122625D02*
X266264D01*
G01X261100Y124239D02*
X262714Y122625D01*
G01X261100Y127300D02*
Y124239D01*
G01X264100Y130300D02*
X261100Y127300D01*
G01Y138200D02*
X264100Y135200D01*
G01X262175Y121325D02*
X265724D01*
G01X259800Y123700D02*
X262175Y121325D01*
G01X259800Y127839D02*
Y123700D01*
G01X262800Y130839D02*
X259800Y127839D01*
G01X262800Y134661D02*
Y130839D01*
G01X259800Y137661D02*
X262800Y134661D01*
G01X261100Y156395D02*
Y138200D01*
G01X259800Y156934D02*
Y137661D01*
G01X269730Y165025D02*
X261100Y156395D01*
G01X269191Y166325D02*
X259800Y156934D01*
G01X267638Y170076D02*
X256050Y158488D01*
G01X268177Y168776D02*
X257350Y157949D01*
G01X253700Y171900D02*
Y168114D01*
G01X266850Y185050D02*
X253700Y171900D01*
G01X255000Y171361D02*
Y167575D01*
G01X267389Y183750D02*
X255000Y171361D01*
G01X249950Y176931D02*
Y170264D01*
G01X252419Y179400D02*
X249950Y176931D01*
G01X255600Y179400D02*
X252419D01*
G01X265000Y188800D02*
X255600Y179400D01*
G01X251250Y176392D02*
Y169725D01*
G01X252958Y178100D02*
X251250Y176392D01*
G01X256139Y178100D02*
X252958D01*
G01X265539Y187500D02*
X256139Y178100D01*
G01X254823Y182223D02*
X256900Y184300D01*
G01X251777Y182223D02*
X254823D01*
G01X260539Y194700D02*
X267350D01*
G01X256900Y191061D02*
X260539Y194700D01*
G01X256900Y184300D02*
Y191061D01*
G01X254284Y183523D02*
X251238D01*
G01X255600Y184839D02*
X254284Y183523D01*
G01X255600Y191600D02*
Y184839D01*
G01X260000Y196000D02*
X255600Y191600D01*
G01X266811Y196000D02*
X260000D01*
G01X249990Y188502D02*
X248802D01*
G01X250944Y189456D02*
X249990Y188502D01*
G01X250944Y190644D02*
Y189456D01*
G01X258750Y198450D02*
X250944Y190644D01*
G01X265796Y198450D02*
X258750D01*
G01X265257Y199750D02*
X258211D01*
G01X262688Y205950D02*
X251650D01*
G01X265600Y208862D02*
X262688Y205950D01*
G01X262149Y207250D02*
X251111D01*
G01X264300Y209401D02*
X262149Y207250D01*
G01X264242Y202200D02*
X257196D01*
G01X263703Y203500D02*
X256657D01*
G01X264953Y204750D02*
X263703Y203500D01*
G01X260807Y212268D02*
X258239Y209700D01*
G01X260807Y215735D02*
Y212268D01*
G01X259507Y212807D02*
X257700Y211000D01*
G01X259507Y216274D02*
Y212807D01*
G01X265355Y220283D02*
X260807Y215735D01*
G01X269197Y225964D02*
X259507Y216274D01*
G01X256777Y217034D02*
X274443Y234700D01*
G01X256238Y218334D02*
X273904Y236000D01*
G01X250940Y221310D02*
X250100Y222150D01*
G01X252290Y221310D02*
X250940D01*
G01X253130Y222150D02*
X252290Y221310D01*
G01X256589Y222150D02*
X253130D01*
G01X274389Y239950D02*
X256589Y222150D01*
G01X273850Y241250D02*
X256050Y223450D01*
G01X273350Y246150D02*
X254400Y227200D01*
G01X273889Y244850D02*
X254939Y225900D01*
G01X269000Y58500D02*
X268000Y57500D01*
G01X269000Y72300D02*
Y58500D01*
G01X270300Y58200D02*
X271000Y57500D01*
G01X270300Y72839D02*
Y58200D01*
G01X265475Y75825D02*
X269000Y72300D01*
G01X266014Y77125D02*
X270300Y72839D01*
G01X275350Y101888D02*
X281263Y95975D01*
G01X275350Y113539D02*
Y101888D01*
G01X274050Y101349D02*
X280724Y94675D01*
G01X274050Y113000D02*
Y101349D01*
G01X278979Y90925D02*
X280856D01*
G01X269700Y100204D02*
X278979Y90925D01*
G01X269700Y101524D02*
Y100204D01*
G01X265390Y105834D02*
X269700Y101524D01*
G01X271000Y100743D02*
X279518Y92225D01*
G01X271000Y102063D02*
Y100743D01*
G01X266690Y106373D02*
X271000Y102063D01*
G01X271789Y117100D02*
X275350Y113539D01*
G01X269339Y117100D02*
X271789D01*
G01X268325Y118114D02*
X269339Y117100D01*
G01X268325Y120563D02*
Y118114D01*
G01X266264Y122625D02*
X268325Y120563D01*
G01X271250Y115800D02*
X274050Y113000D01*
G01X268800Y115800D02*
X271250D01*
G01X267025Y117575D02*
X268800Y115800D01*
G01X267025Y120024D02*
Y117575D01*
G01X265724Y121325D02*
X267025Y120024D01*
G01X265390Y112756D02*
Y105834D01*
G01X266690Y113295D02*
Y106373D01*
G01X264100Y135200D02*
Y130300D01*
G01X271725Y165025D02*
X269730D01*
G01X276450Y169750D02*
X271725Y165025D01*
G01X271186Y166325D02*
X269191D01*
G01X275911Y171050D02*
X271186Y166325D01*
G01X281180Y169750D02*
X276450D01*
G01X287900Y171050D02*
X275911D01*
G01X269537Y170076D02*
X267638D01*
G01X276271Y176810D02*
X269537Y170076D01*
G01X285905Y176810D02*
X276271D01*
G01X270076Y168776D02*
X268177D01*
G01X276810Y175510D02*
X270076Y168776D01*
G01X286444Y175510D02*
X276810D01*
G01X273061Y185050D02*
X266850D01*
G01X275436Y187425D02*
X273061Y185050D01*
G01X288025Y187425D02*
X275436D01*
G01X273600Y183750D02*
X267389D01*
G01X275975Y186125D02*
X273600Y183750D01*
G01X288564Y186125D02*
X275975D01*
G01X265761Y188800D02*
X265000D01*
G01X269561Y192600D02*
X265761Y188800D01*
G01X280086Y192600D02*
X269561D01*
G01X266300Y187500D02*
X265539D01*
G01X270100Y191300D02*
X266300Y187500D01*
G01X280625Y191300D02*
X270100D01*
G01X278643Y195950D02*
X281727Y199034D01*
G01X277393Y195950D02*
X278643D01*
G01X276553Y195110D02*
X277393Y195950D01*
G01X275203Y195110D02*
X276553D01*
G01X274363Y195950D02*
X275203Y195110D01*
G01X273013Y195950D02*
X274363D01*
G01X272173Y195110D02*
X273013Y195950D01*
G01X270823Y195110D02*
X272173D01*
G01X269983Y195950D02*
X270823Y195110D01*
G01X268600Y195950D02*
X269983D01*
G01X267350Y194700D02*
X268600Y195950D01*
G01X268061Y197250D02*
X266811Y196000D01*
G01X278104Y197250D02*
X268061D01*
G01X290879Y210025D02*
X278104Y197250D01*
G01X267046Y199700D02*
X265796Y198450D01*
G01X272839Y199700D02*
X267046D01*
G01X278751Y205612D02*
X272839Y199700D01*
G01X279939Y205612D02*
X278751D01*
G01X266507Y201000D02*
X265257Y199750D01*
G01X272300Y201000D02*
X266507D01*
G01X287525Y216225D02*
X272300Y201000D01*
G01X265600Y211042D02*
Y208862D01*
G01X272958Y218400D02*
X265600Y211042D01*
G01X264300Y211581D02*
Y209401D01*
G01X272419Y219700D02*
X264300Y211581D01*
G01X265492Y203450D02*
X264242Y202200D01*
G01X271085Y203450D02*
X265492D01*
G01X286310Y218675D02*
X271085Y203450D01*
G01X270546Y204750D02*
X264953D01*
G01X285771Y219975D02*
X270546Y204750D01*
G01X275700Y218400D02*
X272958D01*
G01X284500Y227200D02*
X275700Y218400D01*
G01X275161Y219700D02*
X272419D01*
G01X283961Y228500D02*
X275161Y219700D01*
G01X266543Y220283D02*
X265355D01*
G01X267497Y221237D02*
X266543Y220283D01*
G01X267497Y222425D02*
Y221237D01*
G01X269736Y224664D02*
X267497Y222425D01*
G01X275064Y224664D02*
X269736D01*
G01X276800Y226400D02*
X275064Y224664D01*
G01X276800Y230100D02*
Y226400D01*
G01X274525Y225964D02*
X269197D01*
G01X275500Y226939D02*
X274525Y225964D01*
G01X275500Y230639D02*
Y226939D01*
G01X277650Y230950D02*
X276800Y230100D01*
G01X279000Y230950D02*
X277650D01*
G01X279840Y230110D02*
X279000Y230950D01*
G01X277111Y232250D02*
X275500Y230639D01*
G01X325564Y232250D02*
X277111D01*
G01X274443Y234700D02*
X325547D01*
G01X273904Y236000D02*
X326086D01*
G01X277200Y239950D02*
X274389D01*
G01X278700Y238450D02*
X277200Y239950D01*
G01X284939Y238450D02*
X278700D01*
G01X277739Y241250D02*
X273850D01*
G01X279239Y239750D02*
X277739Y241250D01*
G01X284400Y239750D02*
X279239D01*
G01X278591Y244010D02*
X277751Y244850D01*
G01X279941Y244010D02*
X278591D01*
G01X353349Y246150D02*
X273350D01*
G01X277751Y244850D02*
X273889D01*
G01X287800Y58900D02*
X286800Y57900D01*
G01X287800Y61554D02*
Y58900D01*
G01X289100Y59000D02*
X290200Y57900D01*
G01X289100Y62093D02*
Y59000D01*
G01X294300Y84624D02*
X311093Y67831D01*
G01X294300Y88400D02*
Y84624D01*
G01X291987Y90713D02*
X294300Y88400D01*
G01X293000Y84085D02*
X309793Y67292D01*
G01X293000Y87861D02*
Y84085D01*
G01X291448Y89413D02*
X293000Y87861D01*
G01X288751Y89413D02*
X291448D01*
G01X288750Y89412D02*
X288751Y89413D01*
G01X287674Y89412D02*
X288750D01*
G01X282411Y94675D02*
X287674Y89412D01*
G01X290180Y81600D02*
X298991Y72790D01*
G01X286400Y81600D02*
X290180D01*
G01X283941Y84059D02*
X286400Y81600D01*
G01X283941Y87840D02*
Y84059D01*
G01X280856Y90925D02*
X283941Y87840D01*
G01X290719Y82900D02*
X300291Y73329D01*
G01X286939Y82900D02*
X290719D01*
G01X285241Y84598D02*
X286939Y82900D01*
G01X285241Y88379D02*
Y84598D01*
G01X281395Y92225D02*
X285241Y88379D01*
G01X288212Y90713D02*
X291987D01*
G01X282950Y95975D02*
X288212Y90713D01*
G01X281263Y95975D02*
X282950D01*
G01X280724Y94675D02*
X282411D01*
G01X279518Y92225D02*
X281395D01*
G01X282020Y168910D02*
X281180Y169750D01*
G01X283370Y168910D02*
X282020D01*
G01X284210Y169750D02*
X283370Y168910D01*
G01X288439Y169750D02*
X284210D01*
G01X299650Y180961D02*
X288439Y169750D01*
G01X298350Y181500D02*
X287900Y171050D01*
G01X293250Y184155D02*
X285905Y176810D01*
G01X288356Y177422D02*
X286444Y175510D01*
G01X289544Y177422D02*
X288356D01*
G01X290498Y178376D02*
X289544Y177422D01*
G01X290498Y179564D02*
Y178376D01*
G01X291453Y180519D02*
X290498Y179564D01*
G01X292641Y180519D02*
X291453D01*
G01X293595Y181473D02*
X292641Y180519D01*
G01X293595Y182661D02*
Y181473D01*
G01X293250Y194789D02*
Y184155D01*
G01X302000Y203539D02*
X293250Y194789D01*
G01X294550Y183616D02*
X293595Y182661D01*
G01X294550Y194250D02*
Y183616D01*
G01X303300Y203000D02*
X294550Y194250D01*
G01X289500Y188900D02*
X288025Y187425D01*
G01X289500Y196539D02*
Y188900D01*
G01X303536Y210575D02*
X289500Y196539D01*
G01X290800Y188361D02*
X288564Y186125D01*
G01X290800Y196000D02*
Y188361D01*
G01X304075Y209275D02*
X290800Y196000D01*
G01X293761Y206275D02*
X280086Y192600D01*
G01X294300Y204975D02*
X280625Y191300D01*
G01X294736Y206275D02*
X293761D01*
G01X302386Y213925D02*
X294736Y206275D01*
G01X295275Y204975D02*
X294300D01*
G01X291418Y208725D02*
X294925D01*
G01X290063Y207370D02*
X291418Y208725D01*
G01X290063Y206182D02*
Y207370D01*
G01X289109Y205228D02*
X290063Y206182D01*
G01X287921Y205228D02*
X289109D01*
G01X286966Y204273D02*
X287921Y205228D01*
G01X286966Y203085D02*
Y204273D01*
G01X286012Y202131D02*
X286966Y203085D01*
G01X284824Y202131D02*
X286012D01*
G01X283869Y201176D02*
X284824Y202131D01*
G01X283869Y199988D02*
Y201176D01*
G01X282915Y199034D02*
X283869Y199988D01*
G01X281727Y199034D02*
X282915D01*
G01X294386Y210025D02*
X290879D01*
G01X301222Y216861D02*
X294386Y210025D01*
G01X280893Y206566D02*
X279939Y205612D01*
G01X280893Y207754D02*
Y206566D01*
G01X281848Y208709D02*
X280893Y207754D01*
G01X283036Y208709D02*
X281848D01*
G01X283990Y209663D02*
X283036Y208709D01*
G01X283990Y210851D02*
Y209663D01*
G01X288064Y214925D02*
X283990Y210851D01*
G01X295815Y214925D02*
X288064D01*
G01X295276Y216225D02*
X287525D01*
G01X324815Y227200D02*
X284500D01*
G01X325354Y228500D02*
X283961D01*
G01X294481Y218675D02*
X286310D01*
G01X296706Y220900D02*
X294481Y218675D01*
G01X293942Y219975D02*
X285771D01*
G01X296167Y222200D02*
X293942Y219975D01*
G01X281190Y230110D02*
X279840D01*
G01X282030Y230950D02*
X281190Y230110D01*
G01X325025Y230950D02*
X282030D01*
G01X286439Y239950D02*
X284939Y238450D01*
G01X301050Y239950D02*
X286439D01*
G01X285900Y241250D02*
X284400Y239750D01*
G01X301589Y241250D02*
X285900D01*
G01X280781Y244850D02*
X279941Y244010D01*
G01X282971D02*
X282131Y244850D01*
G01X284321Y244010D02*
X282971D01*
G01X285161Y244850D02*
X284321Y244010D01*
G01X287351D02*
X286511Y244850D01*
G01X288701Y244010D02*
X287351D01*
G01X289541Y244850D02*
X288701Y244010D01*
G01X282131Y244850D02*
X280781D01*
G01X286511D02*
X285161D01*
G01X302002D02*
X289541D01*
G01X305900Y58500D02*
X304800Y57400D01*
G01X305900Y64500D02*
Y58500D01*
G01X307200Y58400D02*
X308200Y57400D01*
G01X307200Y65039D02*
Y58400D01*
G01X309793Y63507D02*
X312400Y60900D01*
G01X309793Y67292D02*
Y63507D01*
G01X304300Y66100D02*
X305900Y64500D01*
G01X301900Y66100D02*
X304300D01*
G01X298991Y69009D02*
X301900Y66100D01*
G01X298991Y72790D02*
Y69009D01*
G01X304839Y67400D02*
X307200Y65039D01*
G01X302439Y67400D02*
X304839D01*
G01X300291Y69548D02*
X302439Y67400D01*
G01X300291Y73329D02*
Y69548D01*
G01X299650Y194237D02*
Y180961D01*
G01X298350Y194776D02*
Y181500D01*
G01X302963Y197550D02*
X299650Y194237D01*
G01X309689Y197550D02*
X302963D01*
G01X311339Y199200D02*
X309689Y197550D01*
G01X302424Y198850D02*
X298350Y194776D01*
G01X309150Y198850D02*
X302424D01*
G01X310800Y200500D02*
X309150Y198850D01*
G01X302000Y204439D02*
Y203539D01*
G01X303861Y206300D02*
X302000Y204439D01*
G01X306900Y206300D02*
X303861D01*
G01X308500Y204700D02*
X306900Y206300D01*
G01X325639Y204700D02*
X308500D01*
G01X303300Y203900D02*
Y203000D01*
G01X304400Y205000D02*
X303300Y203900D01*
G01X306361Y205000D02*
X304400D01*
G01X307961Y203400D02*
X306361Y205000D01*
G01X309311Y203400D02*
X307961D01*
G01X310151Y202560D02*
X309311Y203400D01*
G01X321175Y210575D02*
X303536D01*
G01X321025Y209275D02*
X304075D01*
G01X302925Y212625D02*
X295275Y204975D01*
G01X308115Y212625D02*
X302925D01*
G01X308955Y211785D02*
X308115Y212625D01*
G01X310305Y211785D02*
X308955D01*
G01X294925Y208725D02*
X301761Y215561D01*
G01X314261Y213925D02*
X302386D01*
G01X301761Y215561D02*
X313611D01*
G01X313072Y216861D02*
X301222D01*
G01X299059Y218169D02*
X295815Y214925D01*
G01X312269Y218169D02*
X299059D01*
G01X298520Y219469D02*
X295276Y216225D01*
G01X311730Y219469D02*
X298520D01*
G01X310900Y220900D02*
X296706D01*
G01X310361Y222200D02*
X296167D01*
G01X302550Y238450D02*
X301050Y239950D01*
G01X309389Y238450D02*
X302550D01*
G01X310889Y239950D02*
X309389Y238450D01*
G01X303089Y239750D02*
X301589Y241250D01*
G01X308850Y239750D02*
X303089D01*
G01X310350Y241250D02*
X308850Y239750D01*
G01X302842Y244010D02*
X302002Y244850D01*
G01X304192Y244010D02*
X302842D01*
G01X305032Y244850D02*
X304192Y244010D01*
G01X307222D02*
X306382Y244850D01*
G01X308572Y244010D02*
X307222D01*
G01X309412Y244850D02*
X308572Y244010D01*
G01X306382Y244850D02*
X305032D01*
G01X310762D02*
X309412D01*
G01X325320Y42720D02*
X330206D01*
G01X322100Y39500D02*
X325320Y42720D01*
G01X322100Y38100D02*
Y39500D01*
G01X319550Y35550D02*
X322100Y38100D01*
G01X323400Y37561D02*
X320089Y34250D01*
G01X323400Y38961D02*
Y37561D01*
G01X325859Y41420D02*
X323400Y38961D01*
G01X318262Y58338D02*
X319200Y57400D01*
G01X318262Y60663D02*
Y58338D01*
G01X316962Y58562D02*
X315800Y57400D01*
G01X316962Y60124D02*
Y58562D01*
G01X316725Y62200D02*
X318262Y60663D01*
G01X312939Y62200D02*
X316725D01*
G01X311093Y64046D02*
X312939Y62200D01*
G01X311093Y67831D02*
Y64046D01*
G01X316186Y60900D02*
X316962Y60124D01*
G01X312400Y60900D02*
X316186D01*
G01X318800Y196900D02*
X316500Y199200D01*
G01X323096Y196900D02*
X318800D01*
G01X323300Y196696D02*
X323096Y196900D01*
G01X323331Y196696D02*
X323300D01*
G01X316500Y199200D02*
X311339D01*
G01X317039Y200500D02*
X310800D01*
G01X319339Y198200D02*
X317039Y200500D01*
G01X321838Y198200D02*
X319339D01*
G01X322256Y198618D02*
X321838Y198200D01*
G01X311501Y202560D02*
X310151D01*
G01X312341Y203400D02*
X311501Y202560D01*
G01X313691Y203400D02*
X312341D01*
G01X314531Y202560D02*
X313691Y203400D01*
G01X315881Y202560D02*
X314531D01*
G01X316721Y203400D02*
X315881Y202560D01*
G01X318071Y203400D02*
X316721D01*
G01X318911Y202560D02*
X318071Y203400D01*
G01X320261Y202560D02*
X318911D01*
G01X321101Y203400D02*
X320261Y202560D01*
G01X325100Y203400D02*
X321101D01*
G01X325642Y202858D02*
X325100Y203400D01*
G01X321600Y211000D02*
X321175Y210575D01*
G01X321600Y208700D02*
X321025Y209275D01*
G01X311145Y212625D02*
X310305Y211785D01*
G01X314800Y212625D02*
X311145D01*
G01X315600Y213425D02*
X314800Y212625D01*
G01X317200Y213100D02*
X316875Y213425D01*
G01X315061Y214725D02*
X314261Y213925D01*
G01X316625Y214725D02*
X315061D01*
G01X317200Y215300D02*
X316625Y214725D01*
G01X316875Y213425D02*
X315600D01*
G01X315500Y217450D02*
X316600D01*
G01X313611Y215561D02*
X315500Y217450D01*
G01X314961Y218750D02*
X313072Y216861D01*
G01X316600Y218750D02*
X314961D01*
G01X314300Y220200D02*
X312269Y218169D01*
G01X316300Y220200D02*
X314300D01*
G01X313761Y221500D02*
X311730Y219469D01*
G01X316300Y221500D02*
X313761D01*
G01X325421Y226594D02*
X324815Y227200D01*
G01X326340Y227514D02*
X325354Y228500D01*
G01X313700Y223700D02*
X310900Y220900D01*
G01X325346Y223700D02*
X313700D01*
G01X325873Y223173D02*
X325346Y223700D01*
G01X313161Y225000D02*
X310361Y222200D01*
G01X325885Y225000D02*
X313161D01*
G01X331184Y224791D02*
X325025Y230950D01*
G01X332104Y225710D02*
X325564Y232250D01*
G01X325547Y234700D02*
X334337Y225910D01*
G01X330156Y239950D02*
X310889D01*
G01X330695Y241250D02*
X310350D01*
G01X311602Y244010D02*
X310762Y244850D01*
G01X312952Y244010D02*
X311602D01*
G01X313792Y244850D02*
X312952Y244010D01*
G01X329060Y244850D02*
X313792D01*
G01X330206Y42720D02*
X331931Y40995D01*
G01X327878Y41420D02*
X325859D01*
G01X328303Y40995D02*
X327878Y41420D01*
G01X326437Y203902D02*
X325639Y204700D01*
G01X327216Y203902D02*
X326437D01*
G01X325642Y202325D02*
Y202858D01*
G01X326660Y224225D02*
X325885Y225000D01*
G01X326793Y224093D02*
X326660Y224225D01*
G01X326086Y236000D02*
X335256Y226830D01*
G01X336502Y233604D02*
X330156Y239950D01*
G01X337421Y234524D02*
X330695Y241250D01*
G01X329900Y244010D02*
X329060Y244850D01*
G01X331250Y244010D02*
X329900D01*
G01X332090Y244850D02*
X331250Y244010D01*
G01X334280D02*
X333440Y244850D01*
G01X335630Y244010D02*
X334280D01*
G01X336470Y244850D02*
X335630Y244010D01*
G01X338660D02*
X337820Y244850D01*
G01X340010Y244010D02*
X338660D01*
G01X340850Y244850D02*
X340010Y244010D01*
G01X333440Y244850D02*
X332090D01*
G01X337820D02*
X336470D01*
G01X342200D02*
X340850D01*
G01X362900Y236599D02*
X353349Y246150D01*
G01X343040Y244010D02*
X342200Y244850D01*
G01X344390Y244010D02*
X343040D01*
G01X345230Y244850D02*
X344390Y244010D01*
G01X347420D02*
X346580Y244850D01*
G01X348770Y244010D02*
X347420D01*
G01X349610Y244850D02*
X348770Y244010D01*
G01X361600Y236060D02*
X352810Y244850D01*
G01X346580D02*
X345230D01*
G01X352810D02*
X349610D01*
G01X362900Y225900D02*
Y236599D01*
G01X360850Y223850D02*
X362900Y225900D01*
G01X360850Y217811D02*
Y223850D01*
G01X359827Y216788D02*
X360850Y217811D01*
G01X359827Y216341D02*
Y216788D01*
G01X361600Y226439D02*
Y236060D01*
G01X359550Y224389D02*
X361600Y226439D01*
G01X359550Y222830D02*
Y224389D01*
G01X358710Y221990D02*
X359550Y222830D01*
G01X358710Y220640D02*
Y221990D01*
G01X359550Y219800D02*
X358710Y220640D01*
G01X359550Y218450D02*
Y219800D01*
G01X358616Y217516D02*
X359550Y218450D01*
G01X357966Y217516D02*
X358616D01*
M02*
